FILE_TYPE = MACRO_DRAWING;
SET COLOR_WIRE YELLOW;
SET COLOR_PROP MONO;
SET COLOR_DOT WHITE;
SET COLOR_ARC YELLOW;
SET COLOR_BODY GREEN;
SET COLOR_NOTE MONO;
SET PROP_DISPLAY VALUE;
SET PAGE_NUMBER P82;
FORCEADD OFFPAGE..3
(1550 5150);
FORCEPROP 2 LAST $XR1 81 
J 0
(1854 5150);
DISPLAY 0.638298 (1854 5150);
PAINT MONO (1854 5150);
FORCEPROP 2 LAST $XR0 59 
J 0
(1764 5150);
DISPLAY 0.638298 (1764 5150);
PAINT MONO (1764 5150);
FORCEPROP 2 LAST PATH I1
J 0
(1750 5225);
DISPLAY 0.787234 (1750 5225);
PAINT MONO (1750 5225);
DISPLAY INVISIBLE (1750 5225);
FORCEPROP 1 LAST COMMENT_BODY TRUE
J 0
(1500 5050);
DISPLAY 0.936170 (1500 5050);
PAINT GREEN (1500 5050);
DISPLAY INVISIBLE (1500 5050);
FORCEPROP 1 LAST OFFPAGE TRUE
J 0
(1875 5025);
DISPLAY 0.936170 (1875 5025);
PAINT GREEN (1875 5025);
DISPLAY INVISIBLE (1875 5025);
FORCEPROP 2 LAST CDS_LIB mstr_standard
J 0
(1550 5150);
DISPLAY 0.787234 (1550 5150);
PAINT MONO (1550 5150);
DISPLAY INVISIBLE (1550 5150);
FORCEADD TAP..6
R 2
(650 4950);
FORCEPROP 3 LASTPIN (600 4950) SIG_NAME M_J_DQS_DP<15>
J 0
(610 4960);
DISPLAY 0.659574 (610 4960);
PAINT MONO (610 4960);
DISPLAY INVISIBLE (610 4960);
FORCEPROP 1 LASTPIN (600 4950) BN 15
J 2
(650 4960);
DISPLAY 0.617021 (650 4960);
PAINT PINK (650 4960);
FORCEPROP 1 LAST PATH I10
J 2
(650 4950);
DISPLAY 0.936170 (650 4950);
PAINT GREEN (650 4950);
DISPLAY INVISIBLE (650 4950);
FORCEPROP 1 LAST HDL_TAP TRUE
J 2
(325 4825);
DISPLAY 1.234043 (325 4825);
PAINT GREEN (325 4825);
DISPLAY INVISIBLE (325 4825);
FORCEPROP 1 LAST BODY_TYPE PLUMBING
J 2
(650 4900);
DISPLAY 1.234043 (650 4900);
PAINT GREEN (650 4900);
DISPLAY INVISIBLE (650 4900);
FORCEPROP 2 LAST CDS_LIB mstr_standard
J 0
(650 4950);
DISPLAY 0.787234 (650 4950);
PAINT MONO (650 4950);
DISPLAY INVISIBLE (650 4950);
FORCEADD TAP..6
R 2
(-1750 1900);
FORCEPROP 3 LASTPIN (-1800 1900) SIG_NAME M_J_DQ<5>
J 0
(-1790 1910);
DISPLAY 0.659574 (-1790 1910);
PAINT MONO (-1790 1910);
DISPLAY INVISIBLE (-1790 1910);
FORCEPROP 1 LASTPIN (-1800 1900) BN 5
J 2
(-1750 1910);
DISPLAY 0.617021 (-1750 1910);
PAINT PINK (-1750 1910);
FORCEPROP 1 LAST PATH I100
J 2
(-1750 1900);
DISPLAY 0.936170 (-1750 1900);
PAINT GREEN (-1750 1900);
DISPLAY INVISIBLE (-1750 1900);
FORCEPROP 1 LAST HDL_TAP TRUE
J 2
(-2075 1775);
DISPLAY 1.234043 (-2075 1775);
PAINT GREEN (-2075 1775);
DISPLAY INVISIBLE (-2075 1775);
FORCEPROP 1 LAST BODY_TYPE PLUMBING
J 2
(-1750 1850);
DISPLAY 1.234043 (-1750 1850);
PAINT GREEN (-1750 1850);
DISPLAY INVISIBLE (-1750 1850);
FORCEPROP 2 LAST CDS_LIB mstr_standard
J 2
(-1750 1900);
DISPLAY 0.787234 (-1750 1900);
PAINT MONO (-1750 1900);
DISPLAY INVISIBLE (-1750 1900);
FORCEADD TAP..6
R 2
(-1750 2000);
FORCEPROP 3 LASTPIN (-1800 2000) SIG_NAME M_J_DQ<7>
J 0
(-1790 2010);
DISPLAY 0.659574 (-1790 2010);
PAINT MONO (-1790 2010);
DISPLAY INVISIBLE (-1790 2010);
FORCEPROP 1 LASTPIN (-1800 2000) BN 7
J 2
(-1750 2010);
DISPLAY 0.617021 (-1750 2010);
PAINT PINK (-1750 2010);
FORCEPROP 1 LAST PATH I101
J 2
(-1750 2000);
DISPLAY 0.936170 (-1750 2000);
PAINT GREEN (-1750 2000);
DISPLAY INVISIBLE (-1750 2000);
FORCEPROP 1 LAST HDL_TAP TRUE
J 2
(-2075 1875);
DISPLAY 1.234043 (-2075 1875);
PAINT GREEN (-2075 1875);
DISPLAY INVISIBLE (-2075 1875);
FORCEPROP 1 LAST BODY_TYPE PLUMBING
J 2
(-1750 1950);
DISPLAY 1.234043 (-1750 1950);
PAINT GREEN (-1750 1950);
DISPLAY INVISIBLE (-1750 1950);
FORCEPROP 2 LAST CDS_LIB mstr_standard
J 2
(-1750 2000);
DISPLAY 0.787234 (-1750 2000);
PAINT MONO (-1750 2000);
DISPLAY INVISIBLE (-1750 2000);
FORCEADD TAP..6
R 2
(-1750 1950);
FORCEPROP 3 LASTPIN (-1800 1950) SIG_NAME M_J_DQ<6>
J 0
(-1790 1960);
DISPLAY 0.659574 (-1790 1960);
PAINT MONO (-1790 1960);
DISPLAY INVISIBLE (-1790 1960);
FORCEPROP 1 LASTPIN (-1800 1950) BN 6
J 2
(-1750 1960);
DISPLAY 0.617021 (-1750 1960);
PAINT PINK (-1750 1960);
FORCEPROP 1 LAST PATH I102
J 2
(-1750 1950);
DISPLAY 0.936170 (-1750 1950);
PAINT GREEN (-1750 1950);
DISPLAY INVISIBLE (-1750 1950);
FORCEPROP 1 LAST HDL_TAP TRUE
J 2
(-2075 1825);
DISPLAY 1.234043 (-2075 1825);
PAINT GREEN (-2075 1825);
DISPLAY INVISIBLE (-2075 1825);
FORCEPROP 1 LAST BODY_TYPE PLUMBING
J 2
(-1750 1900);
DISPLAY 1.234043 (-1750 1900);
PAINT GREEN (-1750 1900);
DISPLAY INVISIBLE (-1750 1900);
FORCEPROP 2 LAST CDS_LIB mstr_standard
J 2
(-1750 1950);
DISPLAY 0.787234 (-1750 1950);
PAINT MONO (-1750 1950);
DISPLAY INVISIBLE (-1750 1950);
FORCEADD TAP..6
R 2
(-1750 2050);
FORCEPROP 3 LASTPIN (-1800 2050) SIG_NAME M_J_DQ<8>
J 0
(-1790 2060);
DISPLAY 0.659574 (-1790 2060);
PAINT MONO (-1790 2060);
DISPLAY INVISIBLE (-1790 2060);
FORCEPROP 1 LASTPIN (-1800 2050) BN 8
J 2
(-1750 2060);
DISPLAY 0.617021 (-1750 2060);
PAINT PINK (-1750 2060);
FORCEPROP 1 LAST PATH I103
J 2
(-1750 2050);
DISPLAY 0.936170 (-1750 2050);
PAINT GREEN (-1750 2050);
DISPLAY INVISIBLE (-1750 2050);
FORCEPROP 1 LAST HDL_TAP TRUE
J 2
(-2075 1925);
DISPLAY 1.234043 (-2075 1925);
PAINT GREEN (-2075 1925);
DISPLAY INVISIBLE (-2075 1925);
FORCEPROP 1 LAST BODY_TYPE PLUMBING
J 2
(-1750 2000);
DISPLAY 1.234043 (-1750 2000);
PAINT GREEN (-1750 2000);
DISPLAY INVISIBLE (-1750 2000);
FORCEPROP 2 LAST CDS_LIB mstr_standard
J 2
(-1750 2050);
DISPLAY 0.787234 (-1750 2050);
PAINT MONO (-1750 2050);
DISPLAY INVISIBLE (-1750 2050);
FORCEADD TAP..6
R 2
(-1750 2100);
FORCEPROP 3 LASTPIN (-1800 2100) SIG_NAME M_J_DQ<9>
J 0
(-1790 2110);
DISPLAY 0.659574 (-1790 2110);
PAINT MONO (-1790 2110);
DISPLAY INVISIBLE (-1790 2110);
FORCEPROP 1 LASTPIN (-1800 2100) BN 9
J 2
(-1750 2110);
DISPLAY 0.617021 (-1750 2110);
PAINT PINK (-1750 2110);
FORCEPROP 1 LAST PATH I104
J 2
(-1750 2100);
DISPLAY 0.936170 (-1750 2100);
PAINT GREEN (-1750 2100);
DISPLAY INVISIBLE (-1750 2100);
FORCEPROP 1 LAST HDL_TAP TRUE
J 2
(-2075 1975);
DISPLAY 1.234043 (-2075 1975);
PAINT GREEN (-2075 1975);
DISPLAY INVISIBLE (-2075 1975);
FORCEPROP 1 LAST BODY_TYPE PLUMBING
J 2
(-1750 2050);
DISPLAY 1.234043 (-1750 2050);
PAINT GREEN (-1750 2050);
DISPLAY INVISIBLE (-1750 2050);
FORCEPROP 2 LAST CDS_LIB mstr_standard
J 2
(-1750 2100);
DISPLAY 0.787234 (-1750 2100);
PAINT MONO (-1750 2100);
DISPLAY INVISIBLE (-1750 2100);
FORCEADD TAP..6
R 2
(-1750 2150);
FORCEPROP 3 LASTPIN (-1800 2150) SIG_NAME M_J_DQ<10>
J 0
(-1790 2160);
DISPLAY 0.659574 (-1790 2160);
PAINT MONO (-1790 2160);
DISPLAY INVISIBLE (-1790 2160);
FORCEPROP 1 LASTPIN (-1800 2150) BN 10
J 2
(-1750 2160);
DISPLAY 0.617021 (-1750 2160);
PAINT PINK (-1750 2160);
FORCEPROP 1 LAST PATH I105
J 2
(-1750 2150);
DISPLAY 0.936170 (-1750 2150);
PAINT GREEN (-1750 2150);
DISPLAY INVISIBLE (-1750 2150);
FORCEPROP 1 LAST HDL_TAP TRUE
J 2
(-2075 2025);
DISPLAY 1.234043 (-2075 2025);
PAINT GREEN (-2075 2025);
DISPLAY INVISIBLE (-2075 2025);
FORCEPROP 1 LAST BODY_TYPE PLUMBING
J 2
(-1750 2100);
DISPLAY 1.234043 (-1750 2100);
PAINT GREEN (-1750 2100);
DISPLAY INVISIBLE (-1750 2100);
FORCEPROP 2 LAST CDS_LIB mstr_standard
J 2
(-1750 2150);
DISPLAY 0.787234 (-1750 2150);
PAINT MONO (-1750 2150);
DISPLAY INVISIBLE (-1750 2150);
FORCEADD TAP..6
R 2
(-1750 1800);
FORCEPROP 3 LASTPIN (-1800 1800) SIG_NAME M_J_DQ<3>
J 0
(-1790 1810);
DISPLAY 0.659574 (-1790 1810);
PAINT MONO (-1790 1810);
DISPLAY INVISIBLE (-1790 1810);
FORCEPROP 1 LASTPIN (-1800 1800) BN 3
J 2
(-1750 1810);
DISPLAY 0.617021 (-1750 1810);
PAINT PINK (-1750 1810);
FORCEPROP 1 LAST PATH I106
J 2
(-1750 1800);
DISPLAY 0.936170 (-1750 1800);
PAINT GREEN (-1750 1800);
DISPLAY INVISIBLE (-1750 1800);
FORCEPROP 1 LAST HDL_TAP TRUE
J 2
(-2075 1675);
DISPLAY 1.234043 (-2075 1675);
PAINT GREEN (-2075 1675);
DISPLAY INVISIBLE (-2075 1675);
FORCEPROP 1 LAST BODY_TYPE PLUMBING
J 2
(-1750 1750);
DISPLAY 1.234043 (-1750 1750);
PAINT GREEN (-1750 1750);
DISPLAY INVISIBLE (-1750 1750);
FORCEPROP 2 LAST CDS_LIB mstr_standard
J 2
(-1750 1800);
DISPLAY 0.787234 (-1750 1800);
PAINT MONO (-1750 1800);
DISPLAY INVISIBLE (-1750 1800);
FORCEADD TAP..6
R 2
(-1750 1850);
FORCEPROP 3 LASTPIN (-1800 1850) SIG_NAME M_J_DQ<4>
J 0
(-1790 1860);
DISPLAY 0.659574 (-1790 1860);
PAINT MONO (-1790 1860);
DISPLAY INVISIBLE (-1790 1860);
FORCEPROP 1 LASTPIN (-1800 1850) BN 4
J 2
(-1750 1860);
DISPLAY 0.617021 (-1750 1860);
PAINT PINK (-1750 1860);
FORCEPROP 1 LAST PATH I107
J 2
(-1750 1850);
DISPLAY 0.936170 (-1750 1850);
PAINT GREEN (-1750 1850);
DISPLAY INVISIBLE (-1750 1850);
FORCEPROP 1 LAST HDL_TAP TRUE
J 2
(-2075 1725);
DISPLAY 1.234043 (-2075 1725);
PAINT GREEN (-2075 1725);
DISPLAY INVISIBLE (-2075 1725);
FORCEPROP 1 LAST BODY_TYPE PLUMBING
J 2
(-1750 1800);
DISPLAY 1.234043 (-1750 1800);
PAINT GREEN (-1750 1800);
DISPLAY INVISIBLE (-1750 1800);
FORCEPROP 2 LAST CDS_LIB mstr_standard
J 2
(-1750 1850);
DISPLAY 0.787234 (-1750 1850);
PAINT MONO (-1750 1850);
DISPLAY INVISIBLE (-1750 1850);
FORCEADD TAP..6
R 2
(-1750 1700);
FORCEPROP 3 LASTPIN (-1800 1700) SIG_NAME M_J_DQ<1>
J 0
(-1790 1710);
DISPLAY 0.659574 (-1790 1710);
PAINT MONO (-1790 1710);
DISPLAY INVISIBLE (-1790 1710);
FORCEPROP 1 LASTPIN (-1800 1700) BN 1
J 2
(-1750 1710);
DISPLAY 0.617021 (-1750 1710);
PAINT PINK (-1750 1710);
FORCEPROP 1 LAST PATH I108
J 2
(-1750 1700);
DISPLAY 0.936170 (-1750 1700);
PAINT GREEN (-1750 1700);
DISPLAY INVISIBLE (-1750 1700);
FORCEPROP 1 LAST HDL_TAP TRUE
J 2
(-2075 1575);
DISPLAY 1.234043 (-2075 1575);
PAINT GREEN (-2075 1575);
DISPLAY INVISIBLE (-2075 1575);
FORCEPROP 1 LAST BODY_TYPE PLUMBING
J 2
(-1750 1650);
DISPLAY 1.234043 (-1750 1650);
PAINT GREEN (-1750 1650);
DISPLAY INVISIBLE (-1750 1650);
FORCEPROP 2 LAST CDS_LIB mstr_standard
J 2
(-1750 1700);
DISPLAY 0.787234 (-1750 1700);
PAINT MONO (-1750 1700);
DISPLAY INVISIBLE (-1750 1700);
FORCEADD TAP..6
R 2
(-1750 1650);
FORCEPROP 3 LASTPIN (-1800 1650) SIG_NAME M_J_DQ<0>
J 0
(-1790 1660);
DISPLAY 0.659574 (-1790 1660);
PAINT MONO (-1790 1660);
DISPLAY INVISIBLE (-1790 1660);
FORCEPROP 1 LASTPIN (-1800 1650) BN 0
J 2
(-1750 1660);
DISPLAY 0.617021 (-1750 1660);
PAINT PINK (-1750 1660);
FORCEPROP 1 LAST PATH I109
J 2
(-1750 1650);
DISPLAY 0.936170 (-1750 1650);
PAINT GREEN (-1750 1650);
DISPLAY INVISIBLE (-1750 1650);
FORCEPROP 1 LAST HDL_TAP TRUE
J 2
(-2075 1525);
DISPLAY 1.234043 (-2075 1525);
PAINT GREEN (-2075 1525);
DISPLAY INVISIBLE (-2075 1525);
FORCEPROP 1 LAST BODY_TYPE PLUMBING
J 2
(-1750 1600);
DISPLAY 1.234043 (-1750 1600);
PAINT GREEN (-1750 1600);
DISPLAY INVISIBLE (-1750 1600);
FORCEPROP 2 LAST CDS_LIB mstr_standard
J 2
(-1750 1650);
DISPLAY 0.787234 (-1750 1650);
PAINT MONO (-1750 1650);
DISPLAY INVISIBLE (-1750 1650);
FORCEADD TAP..6
R 2
(650 4850);
FORCEPROP 3 LASTPIN (600 4850) SIG_NAME M_J_DQS_DP<14>
J 0
(610 4860);
DISPLAY 0.659574 (610 4860);
PAINT MONO (610 4860);
DISPLAY INVISIBLE (610 4860);
FORCEPROP 1 LASTPIN (600 4850) BN 14
J 2
(650 4860);
DISPLAY 0.617021 (650 4860);
PAINT PINK (650 4860);
FORCEPROP 1 LAST PATH I11
J 2
(650 4850);
DISPLAY 0.936170 (650 4850);
PAINT GREEN (650 4850);
DISPLAY INVISIBLE (650 4850);
FORCEPROP 1 LAST HDL_TAP TRUE
J 2
(325 4725);
DISPLAY 1.234043 (325 4725);
PAINT GREEN (325 4725);
DISPLAY INVISIBLE (325 4725);
FORCEPROP 1 LAST BODY_TYPE PLUMBING
J 2
(650 4800);
DISPLAY 1.234043 (650 4800);
PAINT GREEN (650 4800);
DISPLAY INVISIBLE (650 4800);
FORCEPROP 2 LAST CDS_LIB mstr_standard
J 0
(650 4850);
DISPLAY 0.787234 (650 4850);
PAINT MONO (650 4850);
DISPLAY INVISIBLE (650 4850);
FORCEADD TAP..6
R 2
(-1750 1750);
FORCEPROP 3 LASTPIN (-1800 1750) SIG_NAME M_J_DQ<2>
J 0
(-1790 1760);
DISPLAY 0.659574 (-1790 1760);
PAINT MONO (-1790 1760);
DISPLAY INVISIBLE (-1790 1760);
FORCEPROP 1 LASTPIN (-1800 1750) BN 2
J 2
(-1750 1760);
DISPLAY 0.617021 (-1750 1760);
PAINT PINK (-1750 1760);
FORCEPROP 1 LAST PATH I110
J 2
(-1750 1750);
DISPLAY 0.936170 (-1750 1750);
PAINT GREEN (-1750 1750);
DISPLAY INVISIBLE (-1750 1750);
FORCEPROP 1 LAST HDL_TAP TRUE
J 2
(-2075 1625);
DISPLAY 1.234043 (-2075 1625);
PAINT GREEN (-2075 1625);
DISPLAY INVISIBLE (-2075 1625);
FORCEPROP 1 LAST BODY_TYPE PLUMBING
J 2
(-1750 1700);
DISPLAY 1.234043 (-1750 1700);
PAINT GREEN (-1750 1700);
DISPLAY INVISIBLE (-1750 1700);
FORCEPROP 2 LAST CDS_LIB mstr_standard
J 2
(-1750 1750);
DISPLAY 0.787234 (-1750 1750);
PAINT MONO (-1750 1750);
DISPLAY INVISIBLE (-1750 1750);
FORCEADD TAP..6
(-3250 4750);
FORCEPROP 3 LASTPIN (-3200 4750) SIG_NAME M_J_MA<16>
J 0
(-3190 4760);
DISPLAY 0.659574 (-3190 4760);
PAINT MONO (-3190 4760);
DISPLAY INVISIBLE (-3190 4760);
FORCEPROP 1 LASTPIN (-3200 4750) BN 16
J 0
(-3250 4760);
DISPLAY 0.617021 (-3250 4760);
PAINT PINK (-3250 4760);
FORCEPROP 1 LAST PATH I112
J 0
(-3250 4750);
DISPLAY 0.936170 (-3250 4750);
PAINT GREEN (-3250 4750);
DISPLAY INVISIBLE (-3250 4750);
FORCEPROP 1 LAST HDL_TAP TRUE
J 0
(-2925 4625);
DISPLAY 1.234043 (-2925 4625);
PAINT GREEN (-2925 4625);
DISPLAY INVISIBLE (-2925 4625);
FORCEPROP 1 LAST BODY_TYPE PLUMBING
J 0
(-3250 4700);
DISPLAY 1.234043 (-3250 4700);
PAINT GREEN (-3250 4700);
DISPLAY INVISIBLE (-3250 4700);
FORCEPROP 2 LAST CDS_LIB mstr_standard
J 2
(-3250 4750);
DISPLAY 0.787234 (-3250 4750);
PAINT MONO (-3250 4750);
DISPLAY INVISIBLE (-3250 4750);
FORCEADD TAP..6
(-3250 4800);
FORCEPROP 3 LASTPIN (-3200 4800) SIG_NAME M_J_MA<17>
J 0
(-3190 4810);
DISPLAY 0.659574 (-3190 4810);
PAINT MONO (-3190 4810);
DISPLAY INVISIBLE (-3190 4810);
FORCEPROP 1 LASTPIN (-3200 4800) BN 17
J 0
(-3250 4810);
DISPLAY 0.617021 (-3250 4810);
PAINT PINK (-3250 4810);
FORCEPROP 1 LAST PATH I113
J 0
(-3250 4800);
DISPLAY 0.936170 (-3250 4800);
PAINT GREEN (-3250 4800);
DISPLAY INVISIBLE (-3250 4800);
FORCEPROP 1 LAST HDL_TAP TRUE
J 0
(-2925 4675);
DISPLAY 1.234043 (-2925 4675);
PAINT GREEN (-2925 4675);
DISPLAY INVISIBLE (-2925 4675);
FORCEPROP 1 LAST BODY_TYPE PLUMBING
J 0
(-3250 4750);
DISPLAY 1.234043 (-3250 4750);
PAINT GREEN (-3250 4750);
DISPLAY INVISIBLE (-3250 4750);
FORCEPROP 2 LAST CDS_LIB mstr_standard
J 0
(-3250 4800);
DISPLAY 0.787234 (-3250 4800);
PAINT MONO (-3250 4800);
DISPLAY INVISIBLE (-3250 4800);
FORCEADD TAP..6
(-3250 4700);
FORCEPROP 3 LASTPIN (-3200 4700) SIG_NAME M_J_MA<15>
J 0
(-3190 4710);
DISPLAY 0.659574 (-3190 4710);
PAINT MONO (-3190 4710);
DISPLAY INVISIBLE (-3190 4710);
FORCEPROP 1 LASTPIN (-3200 4700) BN 15
J 0
(-3250 4710);
DISPLAY 0.617021 (-3250 4710);
PAINT PINK (-3250 4710);
FORCEPROP 1 LAST PATH I114
J 0
(-3250 4700);
DISPLAY 0.936170 (-3250 4700);
PAINT GREEN (-3250 4700);
DISPLAY INVISIBLE (-3250 4700);
FORCEPROP 1 LAST HDL_TAP TRUE
J 0
(-2925 4575);
DISPLAY 1.234043 (-2925 4575);
PAINT GREEN (-2925 4575);
DISPLAY INVISIBLE (-2925 4575);
FORCEPROP 1 LAST BODY_TYPE PLUMBING
J 0
(-3250 4650);
DISPLAY 1.234043 (-3250 4650);
PAINT GREEN (-3250 4650);
DISPLAY INVISIBLE (-3250 4650);
FORCEPROP 2 LAST CDS_LIB mstr_standard
J 2
(-3250 4700);
DISPLAY 0.787234 (-3250 4700);
PAINT MONO (-3250 4700);
DISPLAY INVISIBLE (-3250 4700);
FORCEADD TAP..6
(-3250 4650);
FORCEPROP 3 LASTPIN (-3200 4650) SIG_NAME M_J_MA<14>
J 0
(-3190 4660);
DISPLAY 0.659574 (-3190 4660);
PAINT MONO (-3190 4660);
DISPLAY INVISIBLE (-3190 4660);
FORCEPROP 1 LASTPIN (-3200 4650) BN 14
J 0
(-3250 4660);
DISPLAY 0.617021 (-3250 4660);
PAINT PINK (-3250 4660);
FORCEPROP 1 LAST PATH I115
J 0
(-3250 4650);
DISPLAY 0.936170 (-3250 4650);
PAINT GREEN (-3250 4650);
DISPLAY INVISIBLE (-3250 4650);
FORCEPROP 1 LAST HDL_TAP TRUE
J 0
(-2925 4525);
DISPLAY 1.234043 (-2925 4525);
PAINT GREEN (-2925 4525);
DISPLAY INVISIBLE (-2925 4525);
FORCEPROP 1 LAST BODY_TYPE PLUMBING
J 0
(-3250 4600);
DISPLAY 1.234043 (-3250 4600);
PAINT GREEN (-3250 4600);
DISPLAY INVISIBLE (-3250 4600);
FORCEPROP 2 LAST CDS_LIB mstr_standard
J 2
(-3250 4650);
DISPLAY 0.787234 (-3250 4650);
PAINT MONO (-3250 4650);
DISPLAY INVISIBLE (-3250 4650);
FORCEADD TAP..6
(-3250 4600);
FORCEPROP 3 LASTPIN (-3200 4600) SIG_NAME M_J_MA<13>
J 0
(-3190 4610);
DISPLAY 0.659574 (-3190 4610);
PAINT MONO (-3190 4610);
DISPLAY INVISIBLE (-3190 4610);
FORCEPROP 1 LASTPIN (-3200 4600) BN 13
J 0
(-3250 4610);
DISPLAY 0.617021 (-3250 4610);
PAINT PINK (-3250 4610);
FORCEPROP 1 LAST PATH I116
J 0
(-3250 4600);
DISPLAY 0.936170 (-3250 4600);
PAINT GREEN (-3250 4600);
DISPLAY INVISIBLE (-3250 4600);
FORCEPROP 1 LAST HDL_TAP TRUE
J 0
(-2925 4475);
DISPLAY 1.234043 (-2925 4475);
PAINT GREEN (-2925 4475);
DISPLAY INVISIBLE (-2925 4475);
FORCEPROP 1 LAST BODY_TYPE PLUMBING
J 0
(-3250 4550);
DISPLAY 1.234043 (-3250 4550);
PAINT GREEN (-3250 4550);
DISPLAY INVISIBLE (-3250 4550);
FORCEPROP 2 LAST CDS_LIB mstr_standard
J 2
(-3250 4600);
DISPLAY 0.787234 (-3250 4600);
PAINT MONO (-3250 4600);
DISPLAY INVISIBLE (-3250 4600);
FORCEADD TAP..6
(-3250 4500);
FORCEPROP 3 LASTPIN (-3200 4500) SIG_NAME M_J_MA<11>
J 0
(-3190 4510);
DISPLAY 0.659574 (-3190 4510);
PAINT MONO (-3190 4510);
DISPLAY INVISIBLE (-3190 4510);
FORCEPROP 1 LASTPIN (-3200 4500) BN 11
J 0
(-3250 4510);
DISPLAY 0.617021 (-3250 4510);
PAINT PINK (-3250 4510);
FORCEPROP 1 LAST PATH I117
J 0
(-3250 4500);
DISPLAY 0.936170 (-3250 4500);
PAINT GREEN (-3250 4500);
DISPLAY INVISIBLE (-3250 4500);
FORCEPROP 1 LAST HDL_TAP TRUE
J 0
(-2925 4375);
DISPLAY 1.234043 (-2925 4375);
PAINT GREEN (-2925 4375);
DISPLAY INVISIBLE (-2925 4375);
FORCEPROP 1 LAST BODY_TYPE PLUMBING
J 0
(-3250 4450);
DISPLAY 1.234043 (-3250 4450);
PAINT GREEN (-3250 4450);
DISPLAY INVISIBLE (-3250 4450);
FORCEPROP 2 LAST CDS_LIB mstr_standard
J 2
(-3250 4500);
DISPLAY 0.787234 (-3250 4500);
PAINT MONO (-3250 4500);
DISPLAY INVISIBLE (-3250 4500);
FORCEADD TAP..6
(-3250 4550);
FORCEPROP 3 LASTPIN (-3200 4550) SIG_NAME M_J_MA<12>
J 0
(-3190 4560);
DISPLAY 0.659574 (-3190 4560);
PAINT MONO (-3190 4560);
DISPLAY INVISIBLE (-3190 4560);
FORCEPROP 1 LASTPIN (-3200 4550) BN 12
J 0
(-3250 4560);
DISPLAY 0.617021 (-3250 4560);
PAINT PINK (-3250 4560);
FORCEPROP 1 LAST PATH I118
J 0
(-3250 4550);
DISPLAY 0.936170 (-3250 4550);
PAINT GREEN (-3250 4550);
DISPLAY INVISIBLE (-3250 4550);
FORCEPROP 1 LAST HDL_TAP TRUE
J 0
(-2925 4425);
DISPLAY 1.234043 (-2925 4425);
PAINT GREEN (-2925 4425);
DISPLAY INVISIBLE (-2925 4425);
FORCEPROP 1 LAST BODY_TYPE PLUMBING
J 0
(-3250 4500);
DISPLAY 1.234043 (-3250 4500);
PAINT GREEN (-3250 4500);
DISPLAY INVISIBLE (-3250 4500);
FORCEPROP 2 LAST CDS_LIB mstr_standard
J 2
(-3250 4550);
DISPLAY 0.787234 (-3250 4550);
PAINT MONO (-3250 4550);
DISPLAY INVISIBLE (-3250 4550);
FORCEADD TAP..6
(-3250 4450);
FORCEPROP 3 LASTPIN (-3200 4450) SIG_NAME M_J_MA<10>
J 0
(-3190 4460);
DISPLAY 0.659574 (-3190 4460);
PAINT MONO (-3190 4460);
DISPLAY INVISIBLE (-3190 4460);
FORCEPROP 1 LASTPIN (-3200 4450) BN 10
J 0
(-3250 4460);
DISPLAY 0.617021 (-3250 4460);
PAINT PINK (-3250 4460);
FORCEPROP 1 LAST PATH I119
J 0
(-3250 4450);
DISPLAY 0.936170 (-3250 4450);
PAINT GREEN (-3250 4450);
DISPLAY INVISIBLE (-3250 4450);
FORCEPROP 1 LAST HDL_TAP TRUE
J 0
(-2925 4325);
DISPLAY 1.234043 (-2925 4325);
PAINT GREEN (-2925 4325);
DISPLAY INVISIBLE (-2925 4325);
FORCEPROP 1 LAST BODY_TYPE PLUMBING
J 0
(-3250 4400);
DISPLAY 1.234043 (-3250 4400);
PAINT GREEN (-3250 4400);
DISPLAY INVISIBLE (-3250 4400);
FORCEPROP 2 LAST CDS_LIB mstr_standard
J 2
(-3250 4450);
DISPLAY 0.787234 (-3250 4450);
PAINT MONO (-3250 4450);
DISPLAY INVISIBLE (-3250 4450);
FORCEADD TAP..6
R 2
(650 4750);
FORCEPROP 3 LASTPIN (600 4750) SIG_NAME M_J_DQS_DP<13>
J 0
(610 4760);
DISPLAY 0.659574 (610 4760);
PAINT MONO (610 4760);
DISPLAY INVISIBLE (610 4760);
FORCEPROP 1 LASTPIN (600 4750) BN 13
J 2
(650 4760);
DISPLAY 0.617021 (650 4760);
PAINT PINK (650 4760);
FORCEPROP 1 LAST PATH I12
J 2
(650 4750);
DISPLAY 0.936170 (650 4750);
PAINT GREEN (650 4750);
DISPLAY INVISIBLE (650 4750);
FORCEPROP 1 LAST HDL_TAP TRUE
J 2
(325 4625);
DISPLAY 1.234043 (325 4625);
PAINT GREEN (325 4625);
DISPLAY INVISIBLE (325 4625);
FORCEPROP 1 LAST BODY_TYPE PLUMBING
J 2
(650 4700);
DISPLAY 1.234043 (650 4700);
PAINT GREEN (650 4700);
DISPLAY INVISIBLE (650 4700);
FORCEPROP 2 LAST CDS_LIB mstr_standard
J 0
(650 4750);
DISPLAY 0.787234 (650 4750);
PAINT MONO (650 4750);
DISPLAY INVISIBLE (650 4750);
FORCEADD TAP..6
(-3250 4400);
FORCEPROP 3 LASTPIN (-3200 4400) SIG_NAME M_J_MA<9>
J 0
(-3190 4410);
DISPLAY 0.659574 (-3190 4410);
PAINT MONO (-3190 4410);
DISPLAY INVISIBLE (-3190 4410);
FORCEPROP 1 LASTPIN (-3200 4400) BN 9
J 0
(-3250 4410);
DISPLAY 0.617021 (-3250 4410);
PAINT PINK (-3250 4410);
FORCEPROP 1 LAST PATH I120
J 0
(-3250 4400);
DISPLAY 0.936170 (-3250 4400);
PAINT GREEN (-3250 4400);
DISPLAY INVISIBLE (-3250 4400);
FORCEPROP 1 LAST HDL_TAP TRUE
J 0
(-2925 4275);
DISPLAY 1.234043 (-2925 4275);
PAINT GREEN (-2925 4275);
DISPLAY INVISIBLE (-2925 4275);
FORCEPROP 1 LAST BODY_TYPE PLUMBING
J 0
(-3250 4350);
DISPLAY 1.234043 (-3250 4350);
PAINT GREEN (-3250 4350);
DISPLAY INVISIBLE (-3250 4350);
FORCEPROP 2 LAST CDS_LIB mstr_standard
J 2
(-3250 4400);
DISPLAY 0.787234 (-3250 4400);
PAINT MONO (-3250 4400);
DISPLAY INVISIBLE (-3250 4400);
FORCEADD TAP..6
(-3250 4350);
FORCEPROP 3 LASTPIN (-3200 4350) SIG_NAME M_J_MA<8>
J 0
(-3190 4360);
DISPLAY 0.659574 (-3190 4360);
PAINT MONO (-3190 4360);
DISPLAY INVISIBLE (-3190 4360);
FORCEPROP 1 LASTPIN (-3200 4350) BN 8
J 0
(-3250 4360);
DISPLAY 0.617021 (-3250 4360);
PAINT PINK (-3250 4360);
FORCEPROP 1 LAST PATH I121
J 0
(-3250 4350);
DISPLAY 0.936170 (-3250 4350);
PAINT GREEN (-3250 4350);
DISPLAY INVISIBLE (-3250 4350);
FORCEPROP 1 LAST HDL_TAP TRUE
J 0
(-2925 4225);
DISPLAY 1.234043 (-2925 4225);
PAINT GREEN (-2925 4225);
DISPLAY INVISIBLE (-2925 4225);
FORCEPROP 1 LAST BODY_TYPE PLUMBING
J 0
(-3250 4300);
DISPLAY 1.234043 (-3250 4300);
PAINT GREEN (-3250 4300);
DISPLAY INVISIBLE (-3250 4300);
FORCEPROP 2 LAST CDS_LIB mstr_standard
J 2
(-3250 4350);
DISPLAY 0.787234 (-3250 4350);
PAINT MONO (-3250 4350);
DISPLAY INVISIBLE (-3250 4350);
FORCEADD TAP..6
(-3250 4250);
FORCEPROP 3 LASTPIN (-3200 4250) SIG_NAME M_J_MA<6>
J 0
(-3190 4260);
DISPLAY 0.659574 (-3190 4260);
PAINT MONO (-3190 4260);
DISPLAY INVISIBLE (-3190 4260);
FORCEPROP 1 LASTPIN (-3200 4250) BN 6
J 0
(-3250 4260);
DISPLAY 0.617021 (-3250 4260);
PAINT PINK (-3250 4260);
FORCEPROP 1 LAST PATH I122
J 0
(-3250 4250);
DISPLAY 0.936170 (-3250 4250);
PAINT GREEN (-3250 4250);
DISPLAY INVISIBLE (-3250 4250);
FORCEPROP 1 LAST HDL_TAP TRUE
J 0
(-2925 4125);
DISPLAY 1.234043 (-2925 4125);
PAINT GREEN (-2925 4125);
DISPLAY INVISIBLE (-2925 4125);
FORCEPROP 1 LAST BODY_TYPE PLUMBING
J 0
(-3250 4200);
DISPLAY 1.234043 (-3250 4200);
PAINT GREEN (-3250 4200);
DISPLAY INVISIBLE (-3250 4200);
FORCEPROP 2 LAST CDS_LIB mstr_standard
J 2
(-3250 4250);
DISPLAY 0.787234 (-3250 4250);
PAINT MONO (-3250 4250);
DISPLAY INVISIBLE (-3250 4250);
FORCEADD TAP..6
(-3250 4300);
FORCEPROP 3 LASTPIN (-3200 4300) SIG_NAME M_J_MA<7>
J 0
(-3190 4310);
DISPLAY 0.659574 (-3190 4310);
PAINT MONO (-3190 4310);
DISPLAY INVISIBLE (-3190 4310);
FORCEPROP 1 LASTPIN (-3200 4300) BN 7
J 0
(-3250 4310);
DISPLAY 0.617021 (-3250 4310);
PAINT PINK (-3250 4310);
FORCEPROP 1 LAST PATH I123
J 0
(-3250 4300);
DISPLAY 0.936170 (-3250 4300);
PAINT GREEN (-3250 4300);
DISPLAY INVISIBLE (-3250 4300);
FORCEPROP 1 LAST HDL_TAP TRUE
J 0
(-2925 4175);
DISPLAY 1.234043 (-2925 4175);
PAINT GREEN (-2925 4175);
DISPLAY INVISIBLE (-2925 4175);
FORCEPROP 1 LAST BODY_TYPE PLUMBING
J 0
(-3250 4250);
DISPLAY 1.234043 (-3250 4250);
PAINT GREEN (-3250 4250);
DISPLAY INVISIBLE (-3250 4250);
FORCEPROP 2 LAST CDS_LIB mstr_standard
J 2
(-3250 4300);
DISPLAY 0.787234 (-3250 4300);
PAINT MONO (-3250 4300);
DISPLAY INVISIBLE (-3250 4300);
FORCEADD TAP..6
(-3250 4200);
FORCEPROP 3 LASTPIN (-3200 4200) SIG_NAME M_J_MA<5>
J 0
(-3190 4210);
DISPLAY 0.659574 (-3190 4210);
PAINT MONO (-3190 4210);
DISPLAY INVISIBLE (-3190 4210);
FORCEPROP 1 LASTPIN (-3200 4200) BN 5
J 0
(-3250 4210);
DISPLAY 0.617021 (-3250 4210);
PAINT PINK (-3250 4210);
FORCEPROP 1 LAST PATH I124
J 0
(-3250 4200);
DISPLAY 0.936170 (-3250 4200);
PAINT GREEN (-3250 4200);
DISPLAY INVISIBLE (-3250 4200);
FORCEPROP 1 LAST HDL_TAP TRUE
J 0
(-2925 4075);
DISPLAY 1.234043 (-2925 4075);
PAINT GREEN (-2925 4075);
DISPLAY INVISIBLE (-2925 4075);
FORCEPROP 1 LAST BODY_TYPE PLUMBING
J 0
(-3250 4150);
DISPLAY 1.234043 (-3250 4150);
PAINT GREEN (-3250 4150);
DISPLAY INVISIBLE (-3250 4150);
FORCEPROP 2 LAST CDS_LIB mstr_standard
J 2
(-3250 4200);
DISPLAY 0.787234 (-3250 4200);
PAINT MONO (-3250 4200);
DISPLAY INVISIBLE (-3250 4200);
FORCEADD TAP..6
(-3250 4100);
FORCEPROP 3 LASTPIN (-3200 4100) SIG_NAME M_J_MA<3>
J 0
(-3190 4110);
DISPLAY 0.659574 (-3190 4110);
PAINT MONO (-3190 4110);
DISPLAY INVISIBLE (-3190 4110);
FORCEPROP 1 LASTPIN (-3200 4100) BN 3
J 0
(-3250 4110);
DISPLAY 0.617021 (-3250 4110);
PAINT PINK (-3250 4110);
FORCEPROP 1 LAST PATH I125
J 0
(-3250 4100);
DISPLAY 0.936170 (-3250 4100);
PAINT GREEN (-3250 4100);
DISPLAY INVISIBLE (-3250 4100);
FORCEPROP 1 LAST HDL_TAP TRUE
J 0
(-2925 3975);
DISPLAY 1.234043 (-2925 3975);
PAINT GREEN (-2925 3975);
DISPLAY INVISIBLE (-2925 3975);
FORCEPROP 1 LAST BODY_TYPE PLUMBING
J 0
(-3250 4050);
DISPLAY 1.234043 (-3250 4050);
PAINT GREEN (-3250 4050);
DISPLAY INVISIBLE (-3250 4050);
FORCEPROP 2 LAST CDS_LIB mstr_standard
J 2
(-3250 4100);
DISPLAY 0.787234 (-3250 4100);
PAINT MONO (-3250 4100);
DISPLAY INVISIBLE (-3250 4100);
FORCEADD TAP..6
(-3250 4150);
FORCEPROP 3 LASTPIN (-3200 4150) SIG_NAME M_J_MA<4>
J 0
(-3190 4160);
DISPLAY 0.659574 (-3190 4160);
PAINT MONO (-3190 4160);
DISPLAY INVISIBLE (-3190 4160);
FORCEPROP 1 LASTPIN (-3200 4150) BN 4
J 0
(-3250 4160);
DISPLAY 0.617021 (-3250 4160);
PAINT PINK (-3250 4160);
FORCEPROP 1 LAST PATH I126
J 0
(-3250 4150);
DISPLAY 0.936170 (-3250 4150);
PAINT GREEN (-3250 4150);
DISPLAY INVISIBLE (-3250 4150);
FORCEPROP 1 LAST HDL_TAP TRUE
J 0
(-2925 4025);
DISPLAY 1.234043 (-2925 4025);
PAINT GREEN (-2925 4025);
DISPLAY INVISIBLE (-2925 4025);
FORCEPROP 1 LAST BODY_TYPE PLUMBING
J 0
(-3250 4100);
DISPLAY 1.234043 (-3250 4100);
PAINT GREEN (-3250 4100);
DISPLAY INVISIBLE (-3250 4100);
FORCEPROP 2 LAST CDS_LIB mstr_standard
J 2
(-3250 4150);
DISPLAY 0.787234 (-3250 4150);
PAINT MONO (-3250 4150);
DISPLAY INVISIBLE (-3250 4150);
FORCEADD TAP..6
(-3250 4050);
FORCEPROP 3 LASTPIN (-3200 4050) SIG_NAME M_J_MA<2>
J 0
(-3190 4060);
DISPLAY 0.659574 (-3190 4060);
PAINT MONO (-3190 4060);
DISPLAY INVISIBLE (-3190 4060);
FORCEPROP 1 LASTPIN (-3200 4050) BN 2
J 0
(-3250 4060);
DISPLAY 0.617021 (-3250 4060);
PAINT PINK (-3250 4060);
FORCEPROP 1 LAST PATH I127
J 0
(-3250 4050);
DISPLAY 0.936170 (-3250 4050);
PAINT GREEN (-3250 4050);
DISPLAY INVISIBLE (-3250 4050);
FORCEPROP 1 LAST HDL_TAP TRUE
J 0
(-2925 3925);
DISPLAY 1.234043 (-2925 3925);
PAINT GREEN (-2925 3925);
DISPLAY INVISIBLE (-2925 3925);
FORCEPROP 1 LAST BODY_TYPE PLUMBING
J 0
(-3250 4000);
DISPLAY 1.234043 (-3250 4000);
PAINT GREEN (-3250 4000);
DISPLAY INVISIBLE (-3250 4000);
FORCEPROP 2 LAST CDS_LIB mstr_standard
J 2
(-3250 4050);
DISPLAY 0.787234 (-3250 4050);
PAINT MONO (-3250 4050);
DISPLAY INVISIBLE (-3250 4050);
FORCEADD TAP..6
(-3250 3950);
FORCEPROP 3 LASTPIN (-3200 3950) SIG_NAME M_J_MA<0>
J 0
(-3190 3960);
DISPLAY 0.659574 (-3190 3960);
PAINT MONO (-3190 3960);
DISPLAY INVISIBLE (-3190 3960);
FORCEPROP 1 LASTPIN (-3200 3950) BN 0
J 0
(-3250 3960);
DISPLAY 0.617021 (-3250 3960);
PAINT PINK (-3250 3960);
FORCEPROP 1 LAST PATH I128
J 0
(-3250 3950);
DISPLAY 0.936170 (-3250 3950);
PAINT GREEN (-3250 3950);
DISPLAY INVISIBLE (-3250 3950);
FORCEPROP 1 LAST HDL_TAP TRUE
J 0
(-2925 3825);
DISPLAY 1.234043 (-2925 3825);
PAINT GREEN (-2925 3825);
DISPLAY INVISIBLE (-2925 3825);
FORCEPROP 1 LAST BODY_TYPE PLUMBING
J 0
(-3250 3900);
DISPLAY 1.234043 (-3250 3900);
PAINT GREEN (-3250 3900);
DISPLAY INVISIBLE (-3250 3900);
FORCEPROP 2 LAST CDS_LIB mstr_standard
J 2
(-3250 3950);
DISPLAY 0.787234 (-3250 3950);
PAINT MONO (-3250 3950);
DISPLAY INVISIBLE (-3250 3950);
FORCEADD TAP..6
(-3250 4000);
FORCEPROP 3 LASTPIN (-3200 4000) SIG_NAME M_J_MA<1>
J 0
(-3190 4010);
DISPLAY 0.659574 (-3190 4010);
PAINT MONO (-3190 4010);
DISPLAY INVISIBLE (-3190 4010);
FORCEPROP 1 LASTPIN (-3200 4000) BN 1
J 0
(-3250 4010);
DISPLAY 0.617021 (-3250 4010);
PAINT PINK (-3250 4010);
FORCEPROP 1 LAST PATH I129
J 0
(-3250 4000);
DISPLAY 0.936170 (-3250 4000);
PAINT GREEN (-3250 4000);
DISPLAY INVISIBLE (-3250 4000);
FORCEPROP 1 LAST HDL_TAP TRUE
J 0
(-2925 3875);
DISPLAY 1.234043 (-2925 3875);
PAINT GREEN (-2925 3875);
DISPLAY INVISIBLE (-2925 3875);
FORCEPROP 1 LAST BODY_TYPE PLUMBING
J 0
(-3250 3950);
DISPLAY 1.234043 (-3250 3950);
PAINT GREEN (-3250 3950);
DISPLAY INVISIBLE (-3250 3950);
FORCEPROP 2 LAST CDS_LIB mstr_standard
J 2
(-3250 4000);
DISPLAY 0.787234 (-3250 4000);
PAINT MONO (-3250 4000);
DISPLAY INVISIBLE (-3250 4000);
FORCEADD TAP..6
R 2
(650 4650);
FORCEPROP 3 LASTPIN (600 4650) SIG_NAME M_J_DQS_DP<12>
J 0
(610 4660);
DISPLAY 0.659574 (610 4660);
PAINT MONO (610 4660);
DISPLAY INVISIBLE (610 4660);
FORCEPROP 1 LASTPIN (600 4650) BN 12
J 2
(650 4660);
DISPLAY 0.617021 (650 4660);
PAINT PINK (650 4660);
FORCEPROP 1 LAST PATH I13
J 2
(650 4650);
DISPLAY 0.936170 (650 4650);
PAINT GREEN (650 4650);
DISPLAY INVISIBLE (650 4650);
FORCEPROP 1 LAST HDL_TAP TRUE
J 2
(325 4525);
DISPLAY 1.234043 (325 4525);
PAINT GREEN (325 4525);
DISPLAY INVISIBLE (325 4525);
FORCEPROP 1 LAST BODY_TYPE PLUMBING
J 2
(650 4600);
DISPLAY 1.234043 (650 4600);
PAINT GREEN (650 4600);
DISPLAY INVISIBLE (650 4600);
FORCEPROP 2 LAST CDS_LIB mstr_standard
J 0
(650 4650);
DISPLAY 0.787234 (650 4650);
PAINT MONO (650 4650);
DISPLAY INVISIBLE (650 4650);
FORCEADD OFFPAGE..1
(-3900 4850);
FORCEPROP 2 LAST $XR1 81 
J 0
(-4211 4850);
DISPLAY 0.638298 (-4211 4850);
PAINT MONO (-4211 4850);
FORCEPROP 2 LAST $XR0 59 
J 0
(-4121 4850);
DISPLAY 0.638298 (-4121 4850);
PAINT MONO (-4121 4850);
FORCEPROP 2 LAST PATH I130
J 0
(-3850 4925);
DISPLAY 0.787234 (-3850 4925);
PAINT MONO (-3850 4925);
DISPLAY INVISIBLE (-3850 4925);
FORCEPROP 1 LAST COMMENT_BODY TRUE
J 0
(-3775 4750);
DISPLAY 0.936170 (-3775 4750);
PAINT GREEN (-3775 4750);
DISPLAY INVISIBLE (-3775 4750);
FORCEPROP 1 LAST OFFPAGE TRUE
J 0
(-3575 4725);
DISPLAY 0.936170 (-3575 4725);
PAINT GREEN (-3575 4725);
DISPLAY INVISIBLE (-3575 4725);
FORCEPROP 2 LAST CDS_LIB mstr_standard
J 0
(-3900 4850);
DISPLAY 0.787234 (-3900 4850);
PAINT MONO (-3900 4850);
DISPLAY INVISIBLE (-3900 4850);
FORCEADD TAP..6
(-3250 3850);
FORCEPROP 3 LASTPIN (-3200 3850) SIG_NAME M_J_BA<1>
J 0
(-3190 3860);
DISPLAY 0.659574 (-3190 3860);
PAINT MONO (-3190 3860);
DISPLAY INVISIBLE (-3190 3860);
FORCEPROP 1 LASTPIN (-3200 3850) BN 1
J 0
(-3250 3860);
DISPLAY 0.617021 (-3250 3860);
PAINT PINK (-3250 3860);
FORCEPROP 1 LAST PATH I131
J 0
(-3250 3850);
DISPLAY 0.936170 (-3250 3850);
PAINT GREEN (-3250 3850);
DISPLAY INVISIBLE (-3250 3850);
FORCEPROP 1 LAST HDL_TAP TRUE
J 0
(-2925 3725);
DISPLAY 1.234043 (-2925 3725);
PAINT GREEN (-2925 3725);
DISPLAY INVISIBLE (-2925 3725);
FORCEPROP 1 LAST BODY_TYPE PLUMBING
J 0
(-3250 3800);
DISPLAY 1.234043 (-3250 3800);
PAINT GREEN (-3250 3800);
DISPLAY INVISIBLE (-3250 3800);
FORCEPROP 2 LAST CDS_LIB mstr_standard
J 0
(-3250 3850);
DISPLAY 0.787234 (-3250 3850);
PAINT MONO (-3250 3850);
DISPLAY INVISIBLE (-3250 3850);
FORCEADD TAP..6
(-3250 3800);
FORCEPROP 3 LASTPIN (-3200 3800) SIG_NAME M_J_BA<0>
J 0
(-3190 3810);
DISPLAY 0.659574 (-3190 3810);
PAINT MONO (-3190 3810);
DISPLAY INVISIBLE (-3190 3810);
FORCEPROP 1 LASTPIN (-3200 3800) BN 0
J 0
(-3250 3810);
DISPLAY 0.617021 (-3250 3810);
PAINT PINK (-3250 3810);
FORCEPROP 1 LAST PATH I132
J 0
(-3250 3800);
DISPLAY 0.936170 (-3250 3800);
PAINT GREEN (-3250 3800);
DISPLAY INVISIBLE (-3250 3800);
FORCEPROP 1 LAST HDL_TAP TRUE
J 0
(-2925 3675);
DISPLAY 1.234043 (-2925 3675);
PAINT GREEN (-2925 3675);
DISPLAY INVISIBLE (-2925 3675);
FORCEPROP 1 LAST BODY_TYPE PLUMBING
J 0
(-3250 3750);
DISPLAY 1.234043 (-3250 3750);
PAINT GREEN (-3250 3750);
DISPLAY INVISIBLE (-3250 3750);
FORCEPROP 2 LAST CDS_LIB mstr_standard
J 0
(-3250 3800);
DISPLAY 0.787234 (-3250 3800);
PAINT MONO (-3250 3800);
DISPLAY INVISIBLE (-3250 3800);
FORCEADD TAP..6
(-3250 3700);
FORCEPROP 3 LASTPIN (-3200 3700) SIG_NAME M_J_BG<0>
J 0
(-3190 3710);
DISPLAY 0.659574 (-3190 3710);
PAINT MONO (-3190 3710);
DISPLAY INVISIBLE (-3190 3710);
FORCEPROP 1 LASTPIN (-3200 3700) BN 0
J 0
(-3250 3710);
DISPLAY 0.617021 (-3250 3710);
PAINT PINK (-3250 3710);
FORCEPROP 1 LAST PATH I133
J 0
(-3250 3700);
DISPLAY 0.936170 (-3250 3700);
PAINT GREEN (-3250 3700);
DISPLAY INVISIBLE (-3250 3700);
FORCEPROP 1 LAST HDL_TAP TRUE
J 0
(-2925 3575);
DISPLAY 1.234043 (-2925 3575);
PAINT GREEN (-2925 3575);
DISPLAY INVISIBLE (-2925 3575);
FORCEPROP 1 LAST BODY_TYPE PLUMBING
J 0
(-3250 3650);
DISPLAY 1.234043 (-3250 3650);
PAINT GREEN (-3250 3650);
DISPLAY INVISIBLE (-3250 3650);
FORCEPROP 2 LAST CDS_LIB mstr_standard
J 0
(-3250 3700);
DISPLAY 0.787234 (-3250 3700);
PAINT MONO (-3250 3700);
DISPLAY INVISIBLE (-3250 3700);
FORCEADD TAP..6
(-3250 3750);
FORCEPROP 3 LASTPIN (-3200 3750) SIG_NAME M_J_BG<1>
J 0
(-3190 3760);
DISPLAY 0.659574 (-3190 3760);
PAINT MONO (-3190 3760);
DISPLAY INVISIBLE (-3190 3760);
FORCEPROP 1 LASTPIN (-3200 3750) BN 1
J 0
(-3250 3760);
DISPLAY 0.617021 (-3250 3760);
PAINT PINK (-3250 3760);
FORCEPROP 1 LAST PATH I134
J 0
(-3250 3750);
DISPLAY 0.936170 (-3250 3750);
PAINT GREEN (-3250 3750);
DISPLAY INVISIBLE (-3250 3750);
FORCEPROP 1 LAST HDL_TAP TRUE
J 0
(-2925 3625);
DISPLAY 1.234043 (-2925 3625);
PAINT GREEN (-2925 3625);
DISPLAY INVISIBLE (-2925 3625);
FORCEPROP 1 LAST BODY_TYPE PLUMBING
J 0
(-3250 3700);
DISPLAY 1.234043 (-3250 3700);
PAINT GREEN (-3250 3700);
DISPLAY INVISIBLE (-3250 3700);
FORCEPROP 2 LAST CDS_LIB mstr_standard
J 0
(-3250 3750);
DISPLAY 0.787234 (-3250 3750);
PAINT MONO (-3250 3750);
DISPLAY INVISIBLE (-3250 3750);
FORCEADD OFFPAGE..1
(-3900 3400);
FORCEPROP 2 LAST $XR1 81 
J 0
(-4211 3400);
DISPLAY 0.638298 (-4211 3400);
PAINT MONO (-4211 3400);
FORCEPROP 2 LAST $XR0 59 
J 0
(-4121 3400);
DISPLAY 0.638298 (-4121 3400);
PAINT MONO (-4121 3400);
FORCEPROP 2 LAST PATH I135
J 0
(-3850 3475);
DISPLAY 0.787234 (-3850 3475);
PAINT MONO (-3850 3475);
DISPLAY INVISIBLE (-3850 3475);
FORCEPROP 1 LAST COMMENT_BODY TRUE
J 0
(-3775 3300);
DISPLAY 0.936170 (-3775 3300);
PAINT GREEN (-3775 3300);
DISPLAY INVISIBLE (-3775 3300);
FORCEPROP 1 LAST OFFPAGE TRUE
J 0
(-3575 3275);
DISPLAY 0.936170 (-3575 3275);
PAINT GREEN (-3575 3275);
DISPLAY INVISIBLE (-3575 3275);
FORCEPROP 2 LAST CDS_LIB mstr_standard
J 0
(-3900 3400);
DISPLAY 0.787234 (-3900 3400);
PAINT MONO (-3900 3400);
DISPLAY INVISIBLE (-3900 3400);
FORCEADD OFFPAGE..1
(-3900 3900);
FORCEPROP 2 LAST $XR1 81 
J 0
(-4211 3900);
DISPLAY 0.638298 (-4211 3900);
PAINT MONO (-4211 3900);
FORCEPROP 2 LAST $XR0 59 
J 0
(-4121 3900);
DISPLAY 0.638298 (-4121 3900);
PAINT MONO (-4121 3900);
FORCEPROP 2 LAST PATH I136
J 0
(-3850 3975);
DISPLAY 0.787234 (-3850 3975);
PAINT MONO (-3850 3975);
DISPLAY INVISIBLE (-3850 3975);
FORCEPROP 1 LAST COMMENT_BODY TRUE
J 0
(-3775 3800);
DISPLAY 0.936170 (-3775 3800);
PAINT GREEN (-3775 3800);
DISPLAY INVISIBLE (-3775 3800);
FORCEPROP 1 LAST OFFPAGE TRUE
J 0
(-3575 3775);
DISPLAY 0.936170 (-3575 3775);
PAINT GREEN (-3575 3775);
DISPLAY INVISIBLE (-3575 3775);
FORCEPROP 2 LAST CDS_LIB mstr_standard
J 0
(-3900 3900);
DISPLAY 0.787234 (-3900 3900);
PAINT MONO (-3900 3900);
DISPLAY INVISIBLE (-3900 3900);
FORCEADD OFFPAGE..1
(-3900 3800);
FORCEPROP 2 LAST $XR1 81 
J 0
(-4211 3800);
DISPLAY 0.638298 (-4211 3800);
PAINT MONO (-4211 3800);
FORCEPROP 2 LAST $XR0 59 
J 0
(-4121 3800);
DISPLAY 0.638298 (-4121 3800);
PAINT MONO (-4121 3800);
FORCEPROP 2 LAST PATH I137
J 0
(-3850 3875);
DISPLAY 0.787234 (-3850 3875);
PAINT MONO (-3850 3875);
DISPLAY INVISIBLE (-3850 3875);
FORCEPROP 1 LAST COMMENT_BODY TRUE
J 0
(-3775 3700);
DISPLAY 0.936170 (-3775 3700);
PAINT GREEN (-3775 3700);
DISPLAY INVISIBLE (-3775 3700);
FORCEPROP 1 LAST OFFPAGE TRUE
J 0
(-3575 3675);
DISPLAY 0.936170 (-3575 3675);
PAINT GREEN (-3575 3675);
DISPLAY INVISIBLE (-3575 3675);
FORCEPROP 2 LAST CDS_LIB mstr_standard
J 0
(-3900 3800);
DISPLAY 0.787234 (-3900 3800);
PAINT MONO (-3900 3800);
DISPLAY INVISIBLE (-3900 3800);
FORCEADD TAP..6
(-3300 2700);
FORCEPROP 3 LASTPIN (-3250 2700) SIG_NAME M_J_ECC<6>
J 0
(-3240 2710);
DISPLAY 0.659574 (-3240 2710);
PAINT MONO (-3240 2710);
DISPLAY INVISIBLE (-3240 2710);
FORCEPROP 1 LASTPIN (-3250 2700) BN 6
J 0
(-3300 2710);
DISPLAY 0.617021 (-3300 2710);
PAINT PINK (-3300 2710);
FORCEPROP 1 LAST PATH I138
J 0
(-3300 2700);
DISPLAY 0.936170 (-3300 2700);
PAINT GREEN (-3300 2700);
DISPLAY INVISIBLE (-3300 2700);
FORCEPROP 1 LAST HDL_TAP TRUE
J 0
(-2975 2575);
DISPLAY 1.234043 (-2975 2575);
PAINT GREEN (-2975 2575);
DISPLAY INVISIBLE (-2975 2575);
FORCEPROP 1 LAST BODY_TYPE PLUMBING
J 0
(-3300 2650);
DISPLAY 1.234043 (-3300 2650);
PAINT GREEN (-3300 2650);
DISPLAY INVISIBLE (-3300 2650);
FORCEPROP 2 LAST CDS_LIB mstr_standard
J 0
(-3300 2700);
DISPLAY 0.787234 (-3300 2700);
PAINT MONO (-3300 2700);
DISPLAY INVISIBLE (-3300 2700);
FORCEADD TAP..6
(-3300 2750);
FORCEPROP 3 LASTPIN (-3250 2750) SIG_NAME M_J_ECC<7>
J 0
(-3240 2760);
DISPLAY 0.659574 (-3240 2760);
PAINT MONO (-3240 2760);
DISPLAY INVISIBLE (-3240 2760);
FORCEPROP 1 LASTPIN (-3250 2750) BN 7
J 0
(-3300 2760);
DISPLAY 0.617021 (-3300 2760);
PAINT PINK (-3300 2760);
FORCEPROP 1 LAST PATH I139
J 0
(-3300 2750);
DISPLAY 0.936170 (-3300 2750);
PAINT GREEN (-3300 2750);
DISPLAY INVISIBLE (-3300 2750);
FORCEPROP 1 LAST HDL_TAP TRUE
J 0
(-2975 2625);
DISPLAY 1.234043 (-2975 2625);
PAINT GREEN (-2975 2625);
DISPLAY INVISIBLE (-2975 2625);
FORCEPROP 1 LAST BODY_TYPE PLUMBING
J 0
(-3300 2700);
DISPLAY 1.234043 (-3300 2700);
PAINT GREEN (-3300 2700);
DISPLAY INVISIBLE (-3300 2700);
FORCEPROP 2 LAST CDS_LIB mstr_standard
J 0
(-3300 2750);
DISPLAY 0.787234 (-3300 2750);
PAINT MONO (-3300 2750);
DISPLAY INVISIBLE (-3300 2750);
FORCEADD PVDDQ_GHJ..1
(-1400 2575);
FORCEPROP 3 LASTPIN (-1400 2525) SIG_NAME PVDDQ_GHJ\g
J 0
(-1390 2535);
DISPLAY 0.659574 (-1390 2535);
PAINT MONO (-1390 2535);
DISPLAY INVISIBLE (-1390 2535);
FORCEPROP 1 LAST HDL_POWER PVDDQ_GHJ
J 1
(-1400 2625);
DISPLAY 0.872340 (-1400 2625);
PAINT GREEN (-1400 2625);
DISPLAY INVISIBLE (-1400 2625);
FORCEPROP 2 LAST ROOM DDR4_CH_J
J 0
(-1400 2675);
DISPLAY 0.787234 (-1400 2675);
PAINT ORANGE (-1400 2675);
DISPLAY INVISIBLE (-1400 2675);
FORCEPROP 1 LAST PATH I14
J 0
(-1350 2600);
DISPLAY 0.872340 (-1350 2600);
PAINT AQUA (-1350 2600);
DISPLAY INVISIBLE (-1350 2600);
FORCEPROP 1 LAST BODY_TYPE PLUMBING
J 0
(-1445 2532);
DISPLAY 0.340426 (-1445 2532);
PAINT GREEN (-1445 2532);
DISPLAY INVISIBLE (-1445 2532);
FORCEPROP 2 LAST CDS_LIB mstr_symbols
J 0
(-1400 2575);
PAINT ORANGE (-1400 2575);
DISPLAY INVISIBLE (-1400 2575);
FORCEPROP 2 LAST BOM_COST MEM
J 0
(-1400 2580);
PAINT ORANGE (-1400 2580);
DISPLAY INVISIBLE (-1400 2580);
FORCEPROP 1 LAST VOLTAGE 1.2V
J 0
(-1445 2532);
DISPLAY 0.340426 (-1445 2532);
PAINT SKYBLUE (-1445 2532);
DISPLAY INVISIBLE (-1445 2532);
FORCEADD TAP..6
(-3300 2650);
FORCEPROP 3 LASTPIN (-3250 2650) SIG_NAME M_J_ECC<5>
J 0
(-3240 2660);
DISPLAY 0.659574 (-3240 2660);
PAINT MONO (-3240 2660);
DISPLAY INVISIBLE (-3240 2660);
FORCEPROP 1 LASTPIN (-3250 2650) BN 5
J 0
(-3300 2660);
DISPLAY 0.617021 (-3300 2660);
PAINT PINK (-3300 2660);
FORCEPROP 1 LAST PATH I140
J 0
(-3300 2650);
DISPLAY 0.936170 (-3300 2650);
PAINT GREEN (-3300 2650);
DISPLAY INVISIBLE (-3300 2650);
FORCEPROP 1 LAST HDL_TAP TRUE
J 0
(-2975 2525);
DISPLAY 1.234043 (-2975 2525);
PAINT GREEN (-2975 2525);
DISPLAY INVISIBLE (-2975 2525);
FORCEPROP 1 LAST BODY_TYPE PLUMBING
J 0
(-3300 2600);
DISPLAY 1.234043 (-3300 2600);
PAINT GREEN (-3300 2600);
DISPLAY INVISIBLE (-3300 2600);
FORCEPROP 2 LAST CDS_LIB mstr_standard
J 0
(-3300 2650);
DISPLAY 0.787234 (-3300 2650);
PAINT MONO (-3300 2650);
DISPLAY INVISIBLE (-3300 2650);
FORCEADD TAP..6
(-3300 2600);
FORCEPROP 3 LASTPIN (-3250 2600) SIG_NAME M_J_ECC<4>
J 0
(-3240 2610);
DISPLAY 0.659574 (-3240 2610);
PAINT MONO (-3240 2610);
DISPLAY INVISIBLE (-3240 2610);
FORCEPROP 1 LASTPIN (-3250 2600) BN 4
J 0
(-3300 2610);
DISPLAY 0.617021 (-3300 2610);
PAINT PINK (-3300 2610);
FORCEPROP 1 LAST PATH I141
J 0
(-3300 2600);
DISPLAY 0.936170 (-3300 2600);
PAINT GREEN (-3300 2600);
DISPLAY INVISIBLE (-3300 2600);
FORCEPROP 1 LAST HDL_TAP TRUE
J 0
(-2975 2475);
DISPLAY 1.234043 (-2975 2475);
PAINT GREEN (-2975 2475);
DISPLAY INVISIBLE (-2975 2475);
FORCEPROP 1 LAST BODY_TYPE PLUMBING
J 0
(-3300 2550);
DISPLAY 1.234043 (-3300 2550);
PAINT GREEN (-3300 2550);
DISPLAY INVISIBLE (-3300 2550);
FORCEPROP 2 LAST CDS_LIB mstr_standard
J 0
(-3300 2600);
DISPLAY 0.787234 (-3300 2600);
PAINT MONO (-3300 2600);
DISPLAY INVISIBLE (-3300 2600);
FORCEADD TAP..6
(-3300 2550);
FORCEPROP 3 LASTPIN (-3250 2550) SIG_NAME M_J_ECC<3>
J 0
(-3240 2560);
DISPLAY 0.659574 (-3240 2560);
PAINT MONO (-3240 2560);
DISPLAY INVISIBLE (-3240 2560);
FORCEPROP 1 LASTPIN (-3250 2550) BN 3
J 0
(-3300 2560);
DISPLAY 0.617021 (-3300 2560);
PAINT PINK (-3300 2560);
FORCEPROP 1 LAST PATH I142
J 0
(-3300 2550);
DISPLAY 0.936170 (-3300 2550);
PAINT GREEN (-3300 2550);
DISPLAY INVISIBLE (-3300 2550);
FORCEPROP 1 LAST HDL_TAP TRUE
J 0
(-2975 2425);
DISPLAY 1.234043 (-2975 2425);
PAINT GREEN (-2975 2425);
DISPLAY INVISIBLE (-2975 2425);
FORCEPROP 1 LAST BODY_TYPE PLUMBING
J 0
(-3300 2500);
DISPLAY 1.234043 (-3300 2500);
PAINT GREEN (-3300 2500);
DISPLAY INVISIBLE (-3300 2500);
FORCEPROP 2 LAST CDS_LIB mstr_standard
J 0
(-3300 2550);
DISPLAY 0.787234 (-3300 2550);
PAINT MONO (-3300 2550);
DISPLAY INVISIBLE (-3300 2550);
FORCEADD TAP..6
(-3300 2450);
FORCEPROP 3 LASTPIN (-3250 2450) SIG_NAME M_J_ECC<1>
J 0
(-3240 2460);
DISPLAY 0.659574 (-3240 2460);
PAINT MONO (-3240 2460);
DISPLAY INVISIBLE (-3240 2460);
FORCEPROP 1 LASTPIN (-3250 2450) BN 1
J 0
(-3300 2460);
DISPLAY 0.617021 (-3300 2460);
PAINT PINK (-3300 2460);
FORCEPROP 1 LAST PATH I143
J 0
(-3300 2450);
DISPLAY 0.936170 (-3300 2450);
PAINT GREEN (-3300 2450);
DISPLAY INVISIBLE (-3300 2450);
FORCEPROP 1 LAST HDL_TAP TRUE
J 0
(-2975 2325);
DISPLAY 1.234043 (-2975 2325);
PAINT GREEN (-2975 2325);
DISPLAY INVISIBLE (-2975 2325);
FORCEPROP 1 LAST BODY_TYPE PLUMBING
J 0
(-3300 2400);
DISPLAY 1.234043 (-3300 2400);
PAINT GREEN (-3300 2400);
DISPLAY INVISIBLE (-3300 2400);
FORCEPROP 2 LAST CDS_LIB mstr_standard
J 0
(-3300 2450);
DISPLAY 0.787234 (-3300 2450);
PAINT MONO (-3300 2450);
DISPLAY INVISIBLE (-3300 2450);
FORCEADD TAP..6
(-3300 2500);
FORCEPROP 3 LASTPIN (-3250 2500) SIG_NAME M_J_ECC<2>
J 0
(-3240 2510);
DISPLAY 0.659574 (-3240 2510);
PAINT MONO (-3240 2510);
DISPLAY INVISIBLE (-3240 2510);
FORCEPROP 1 LASTPIN (-3250 2500) BN 2
J 0
(-3300 2510);
DISPLAY 0.617021 (-3300 2510);
PAINT PINK (-3300 2510);
FORCEPROP 1 LAST PATH I144
J 0
(-3300 2500);
DISPLAY 0.936170 (-3300 2500);
PAINT GREEN (-3300 2500);
DISPLAY INVISIBLE (-3300 2500);
FORCEPROP 1 LAST HDL_TAP TRUE
J 0
(-2975 2375);
DISPLAY 1.234043 (-2975 2375);
PAINT GREEN (-2975 2375);
DISPLAY INVISIBLE (-2975 2375);
FORCEPROP 1 LAST BODY_TYPE PLUMBING
J 0
(-3300 2450);
DISPLAY 1.234043 (-3300 2450);
PAINT GREEN (-3300 2450);
DISPLAY INVISIBLE (-3300 2450);
FORCEPROP 2 LAST CDS_LIB mstr_standard
J 0
(-3300 2500);
DISPLAY 0.787234 (-3300 2500);
PAINT MONO (-3300 2500);
DISPLAY INVISIBLE (-3300 2500);
FORCEADD TAP..6
(-3300 2400);
FORCEPROP 3 LASTPIN (-3250 2400) SIG_NAME M_J_ECC<0>
J 0
(-3240 2410);
DISPLAY 0.659574 (-3240 2410);
PAINT MONO (-3240 2410);
DISPLAY INVISIBLE (-3240 2410);
FORCEPROP 1 LASTPIN (-3250 2400) BN 0
J 0
(-3300 2410);
DISPLAY 0.617021 (-3300 2410);
PAINT PINK (-3300 2410);
FORCEPROP 1 LAST PATH I145
J 0
(-3300 2400);
DISPLAY 0.936170 (-3300 2400);
PAINT GREEN (-3300 2400);
DISPLAY INVISIBLE (-3300 2400);
FORCEPROP 1 LAST HDL_TAP TRUE
J 0
(-2975 2275);
DISPLAY 1.234043 (-2975 2275);
PAINT GREEN (-2975 2275);
DISPLAY INVISIBLE (-2975 2275);
FORCEPROP 1 LAST BODY_TYPE PLUMBING
J 0
(-3300 2350);
DISPLAY 1.234043 (-3300 2350);
PAINT GREEN (-3300 2350);
DISPLAY INVISIBLE (-3300 2350);
FORCEPROP 2 LAST CDS_LIB mstr_standard
J 0
(-3300 2400);
DISPLAY 0.787234 (-3300 2400);
PAINT MONO (-3300 2400);
DISPLAY INVISIBLE (-3300 2400);
FORCEADD OFFPAGE..1
(-3900 2750);
FORCEPROP 2 LAST $XR1 81 
J 0
(-4271 2750);
DISPLAY 0.638298 (-4271 2750);
PAINT MONO (-4271 2750);
FORCEPROP 2 LAST $XR0 59 
J 0
(-4181 2750);
DISPLAY 0.638298 (-4181 2750);
PAINT MONO (-4181 2750);
FORCEPROP 2 LAST PATH I146
J 0
(-3850 2825);
DISPLAY 0.787234 (-3850 2825);
PAINT MONO (-3850 2825);
DISPLAY INVISIBLE (-3850 2825);
FORCEPROP 1 LAST COMMENT_BODY TRUE
J 0
(-3775 2650);
DISPLAY 0.936170 (-3775 2650);
PAINT GREEN (-3775 2650);
DISPLAY INVISIBLE (-3775 2650);
FORCEPROP 1 LAST OFFPAGE TRUE
J 0
(-3575 2625);
DISPLAY 0.936170 (-3575 2625);
PAINT GREEN (-3575 2625);
DISPLAY INVISIBLE (-3575 2625);
FORCEPROP 2 LAST CDS_LIB mstr_standard
J 0
(-3900 2750);
DISPLAY 0.787234 (-3900 2750);
PAINT MONO (-3900 2750);
DISPLAY INVISIBLE (-3900 2750);
FORCEADD OFFPAGE..1
(-4100 2100);
FORCEPROP 2 LAST $XR1 81 
J 0
(-4471 2100);
DISPLAY 0.638298 (-4471 2100);
PAINT MONO (-4471 2100);
FORCEPROP 2 LAST $XR0 59 
J 0
(-4381 2100);
DISPLAY 0.638298 (-4381 2100);
PAINT MONO (-4381 2100);
FORCEPROP 2 LAST PATH I147
J 0
(-4050 2175);
DISPLAY 0.787234 (-4050 2175);
PAINT MONO (-4050 2175);
DISPLAY INVISIBLE (-4050 2175);
FORCEPROP 1 LAST COMMENT_BODY TRUE
J 0
(-3975 2000);
DISPLAY 0.936170 (-3975 2000);
PAINT GREEN (-3975 2000);
DISPLAY INVISIBLE (-3975 2000);
FORCEPROP 1 LAST OFFPAGE TRUE
J 0
(-3775 1975);
DISPLAY 0.936170 (-3775 1975);
PAINT GREEN (-3775 1975);
DISPLAY INVISIBLE (-3775 1975);
FORCEPROP 2 LAST CDS_LIB mstr_standard
J 0
(-4100 2100);
DISPLAY 0.787234 (-4100 2100);
PAINT MONO (-4100 2100);
DISPLAY INVISIBLE (-4100 2100);
FORCEADD OFFPAGE..5
(-4125 2150);
FORCEPROP 2 LAST $XR1 59 
J 0
(-4469 2150);
DISPLAY 0.638298 (-4469 2150);
PAINT MONO (-4469 2150);
FORCEPROP 2 LAST $XR0 81 
J 0
(-4379 2150);
DISPLAY 0.638298 (-4379 2150);
PAINT MONO (-4379 2150);
FORCEPROP 2 LAST PATH I148
J 0
(-4075 2225);
DISPLAY 0.787234 (-4075 2225);
PAINT MONO (-4075 2225);
DISPLAY INVISIBLE (-4075 2225);
FORCEPROP 1 LAST COMMENT_BODY TRUE
J 0
(-4025 2075);
DISPLAY 1.404255 (-4025 2075);
PAINT GREEN (-4025 2075);
DISPLAY INVISIBLE (-4025 2075);
FORCEPROP 1 LAST OFFPAGE TRUE
J 0
(-3800 2025);
DISPLAY 1.404255 (-3800 2025);
PAINT GREEN (-3800 2025);
DISPLAY INVISIBLE (-3800 2025);
FORCEPROP 2 LAST CDS_LIB mstr_standard
J 0
(-4125 2150);
DISPLAY 0.787234 (-4125 2150);
PAINT MONO (-4125 2150);
DISPLAY INVISIBLE (-4125 2150);
FORCEADD OFFPAGE..1
(-3900 2700);
FORCEPROP 2 LAST $XR5 81 
J 0
(-4571 2700);
DISPLAY 0.638298 (-4571 2700);
PAINT MONO (-4571 2700);
FORCEPROP 2 LAST $XR4 80 
J 0
(-4481 2700);
DISPLAY 0.638298 (-4481 2700);
PAINT MONO (-4481 2700);
FORCEPROP 2 LAST $XR3 79 
J 0
(-4391 2700);
DISPLAY 0.638298 (-4391 2700);
PAINT MONO (-4391 2700);
FORCEPROP 2 LAST $XR2 78 
J 0
(-4301 2700);
DISPLAY 0.638298 (-4301 2700);
PAINT MONO (-4301 2700);
FORCEPROP 2 LAST $XR1 77 
J 0
(-4211 2700);
DISPLAY 0.638298 (-4211 2700);
PAINT MONO (-4211 2700);
FORCEPROP 2 LAST $XR0 55 
J 0
(-4121 2700);
DISPLAY 0.638298 (-4121 2700);
PAINT MONO (-4121 2700);
FORCEPROP 2 LAST PATH I149
J 0
(-3850 2775);
DISPLAY 0.787234 (-3850 2775);
PAINT MONO (-3850 2775);
DISPLAY INVISIBLE (-3850 2775);
FORCEPROP 1 LAST COMMENT_BODY TRUE
J 0
(-3775 2600);
DISPLAY 0.936170 (-3775 2600);
PAINT GREEN (-3775 2600);
DISPLAY INVISIBLE (-3775 2600);
FORCEPROP 1 LAST OFFPAGE TRUE
J 0
(-3575 2575);
DISPLAY 0.936170 (-3575 2575);
PAINT GREEN (-3575 2575);
DISPLAY INVISIBLE (-3575 2575);
FORCEPROP 2 LAST CDS_LIB mstr_standard
J 0
(-3900 2700);
DISPLAY 0.787234 (-3900 2700);
PAINT MONO (-3900 2700);
DISPLAY INVISIBLE (-3900 2700);
FORCEADD OFFPAGE..6
(-3900 2800);
FORCEPROP 2 LAST $XR1 81 
J 0
(-4269 2800);
DISPLAY 0.638298 (-4269 2800);
PAINT MONO (-4269 2800);
FORCEPROP 2 LAST $XR0 59 
J 0
(-4179 2800);
DISPLAY 0.638298 (-4179 2800);
PAINT MONO (-4179 2800);
FORCEPROP 2 LAST PATH I150
J 0
(-3850 2875);
DISPLAY 0.787234 (-3850 2875);
PAINT MONO (-3850 2875);
DISPLAY INVISIBLE (-3850 2875);
FORCEPROP 1 LAST COMMENT_BODY TRUE
J 0
(-3800 2725);
DISPLAY 0.936170 (-3800 2725);
PAINT GREEN (-3800 2725);
DISPLAY INVISIBLE (-3800 2725);
FORCEPROP 1 LAST OFFPAGE TRUE
J 0
(-3575 2675);
DISPLAY 0.936170 (-3575 2675);
PAINT GREEN (-3575 2675);
DISPLAY INVISIBLE (-3575 2675);
FORCEPROP 2 LAST CDS_LIB mstr_standard
J 0
(-3900 2800);
DISPLAY 0.787234 (-3900 2800);
PAINT MONO (-3900 2800);
DISPLAY INVISIBLE (-3900 2800);
FORCEADD TAP..6
(-3250 3600);
FORCEPROP 3 LASTPIN (-3200 3600) SIG_NAME M_J_CLK_DP<3>
J 0
(-3190 3610);
DISPLAY 0.659574 (-3190 3610);
PAINT MONO (-3190 3610);
DISPLAY INVISIBLE (-3190 3610);
FORCEPROP 1 LASTPIN (-3200 3600) BN 3
J 0
(-3250 3610);
DISPLAY 0.617021 (-3250 3610);
PAINT PINK (-3250 3610);
FORCEPROP 1 LAST PATH I152
J 0
(-3250 3600);
DISPLAY 0.936170 (-3250 3600);
PAINT GREEN (-3250 3600);
DISPLAY INVISIBLE (-3250 3600);
FORCEPROP 1 LAST HDL_TAP TRUE
J 0
(-2925 3475);
DISPLAY 1.234043 (-2925 3475);
PAINT GREEN (-2925 3475);
DISPLAY INVISIBLE (-2925 3475);
FORCEPROP 1 LAST BODY_TYPE PLUMBING
J 0
(-3250 3550);
DISPLAY 1.234043 (-3250 3550);
PAINT GREEN (-3250 3550);
DISPLAY INVISIBLE (-3250 3550);
FORCEPROP 2 LAST CDS_LIB mstr_standard
J 0
(-3250 3600);
DISPLAY 0.787234 (-3250 3600);
PAINT MONO (-3250 3600);
DISPLAY INVISIBLE (-3250 3600);
FORCEADD TAP..6
(-3250 3500);
FORCEPROP 3 LASTPIN (-3200 3500) SIG_NAME M_J_CLK_DP<2>
J 0
(-3190 3510);
DISPLAY 0.659574 (-3190 3510);
PAINT MONO (-3190 3510);
DISPLAY INVISIBLE (-3190 3510);
FORCEPROP 1 LASTPIN (-3200 3500) BN 2
J 0
(-3250 3510);
DISPLAY 0.617021 (-3250 3510);
PAINT PINK (-3250 3510);
FORCEPROP 1 LAST PATH I153
J 0
(-3250 3500);
DISPLAY 0.936170 (-3250 3500);
PAINT GREEN (-3250 3500);
DISPLAY INVISIBLE (-3250 3500);
FORCEPROP 1 LAST HDL_TAP TRUE
J 0
(-2925 3375);
DISPLAY 1.234043 (-2925 3375);
PAINT GREEN (-2925 3375);
DISPLAY INVISIBLE (-2925 3375);
FORCEPROP 1 LAST BODY_TYPE PLUMBING
J 0
(-3250 3450);
DISPLAY 1.234043 (-3250 3450);
PAINT GREEN (-3250 3450);
DISPLAY INVISIBLE (-3250 3450);
FORCEPROP 2 LAST CDS_LIB mstr_standard
J 0
(-3250 3500);
DISPLAY 0.787234 (-3250 3500);
PAINT MONO (-3250 3500);
DISPLAY INVISIBLE (-3250 3500);
FORCEADD TAP..6
(-3450 3550);
FORCEPROP 3 LASTPIN (-3400 3550) SIG_NAME M_J_CLK_DN<3>
J 0
(-3390 3560);
DISPLAY 0.659574 (-3390 3560);
PAINT MONO (-3390 3560);
DISPLAY INVISIBLE (-3390 3560);
FORCEPROP 1 LASTPIN (-3400 3550) BN 3
J 0
(-3450 3560);
DISPLAY 0.617021 (-3450 3560);
PAINT PINK (-3450 3560);
FORCEPROP 1 LAST PATH I154
J 0
(-3450 3550);
DISPLAY 0.936170 (-3450 3550);
PAINT GREEN (-3450 3550);
DISPLAY INVISIBLE (-3450 3550);
FORCEPROP 1 LAST HDL_TAP TRUE
J 0
(-3125 3425);
DISPLAY 1.234043 (-3125 3425);
PAINT GREEN (-3125 3425);
DISPLAY INVISIBLE (-3125 3425);
FORCEPROP 1 LAST BODY_TYPE PLUMBING
J 0
(-3450 3500);
DISPLAY 1.234043 (-3450 3500);
PAINT GREEN (-3450 3500);
DISPLAY INVISIBLE (-3450 3500);
FORCEPROP 2 LAST CDS_LIB mstr_standard
J 0
(-3450 3550);
DISPLAY 0.787234 (-3450 3550);
PAINT MONO (-3450 3550);
DISPLAY INVISIBLE (-3450 3550);
FORCEADD TAP..6
(-3450 3450);
FORCEPROP 3 LASTPIN (-3400 3450) SIG_NAME M_J_CLK_DN<2>
J 0
(-3390 3460);
DISPLAY 0.659574 (-3390 3460);
PAINT MONO (-3390 3460);
DISPLAY INVISIBLE (-3390 3460);
FORCEPROP 1 LASTPIN (-3400 3450) BN 2
J 0
(-3450 3460);
DISPLAY 0.617021 (-3450 3460);
PAINT PINK (-3450 3460);
FORCEPROP 1 LAST PATH I155
J 0
(-3450 3450);
DISPLAY 0.936170 (-3450 3450);
PAINT GREEN (-3450 3450);
DISPLAY INVISIBLE (-3450 3450);
FORCEPROP 1 LAST HDL_TAP TRUE
J 0
(-3125 3325);
DISPLAY 1.234043 (-3125 3325);
PAINT GREEN (-3125 3325);
DISPLAY INVISIBLE (-3125 3325);
FORCEPROP 1 LAST BODY_TYPE PLUMBING
J 0
(-3450 3400);
DISPLAY 1.234043 (-3450 3400);
PAINT GREEN (-3450 3400);
DISPLAY INVISIBLE (-3450 3400);
FORCEPROP 2 LAST CDS_LIB mstr_standard
J 0
(-3450 3450);
DISPLAY 0.787234 (-3450 3450);
PAINT MONO (-3450 3450);
DISPLAY INVISIBLE (-3450 3450);
FORCEADD OFFPAGE..1
(-3900 3650);
FORCEPROP 2 LAST $XR1 81 
J 0
(-4211 3650);
DISPLAY 0.638298 (-4211 3650);
PAINT MONO (-4211 3650);
FORCEPROP 2 LAST $XR0 59 
J 0
(-4121 3650);
DISPLAY 0.638298 (-4121 3650);
PAINT MONO (-4121 3650);
FORCEPROP 2 LAST PATH I156
J 0
(-3850 3725);
DISPLAY 0.787234 (-3850 3725);
PAINT MONO (-3850 3725);
DISPLAY INVISIBLE (-3850 3725);
FORCEPROP 1 LAST COMMENT_BODY TRUE
J 0
(-3775 3550);
DISPLAY 0.936170 (-3775 3550);
PAINT GREEN (-3775 3550);
DISPLAY INVISIBLE (-3775 3550);
FORCEPROP 1 LAST OFFPAGE TRUE
J 0
(-3575 3525);
DISPLAY 0.936170 (-3575 3525);
PAINT GREEN (-3575 3525);
DISPLAY INVISIBLE (-3575 3525);
FORCEPROP 2 LAST CDS_LIB mstr_standard
J 0
(-3900 3650);
DISPLAY 0.787234 (-3900 3650);
PAINT MONO (-3900 3650);
DISPLAY INVISIBLE (-3900 3650);
FORCEADD OFFPAGE..1
(-3900 3600);
FORCEPROP 2 LAST $XR1 81 
J 0
(-4211 3600);
DISPLAY 0.638298 (-4211 3600);
PAINT MONO (-4211 3600);
FORCEPROP 2 LAST $XR0 59 
J 0
(-4121 3600);
DISPLAY 0.638298 (-4121 3600);
PAINT MONO (-4121 3600);
FORCEPROP 2 LAST PATH I157
J 0
(-3850 3675);
DISPLAY 0.787234 (-3850 3675);
PAINT MONO (-3850 3675);
DISPLAY INVISIBLE (-3850 3675);
FORCEPROP 1 LAST COMMENT_BODY TRUE
J 0
(-3775 3500);
DISPLAY 0.936170 (-3775 3500);
PAINT GREEN (-3775 3500);
DISPLAY INVISIBLE (-3775 3500);
FORCEPROP 1 LAST OFFPAGE TRUE
J 0
(-3575 3475);
DISPLAY 0.936170 (-3575 3475);
PAINT GREEN (-3575 3475);
DISPLAY INVISIBLE (-3575 3475);
FORCEPROP 2 LAST CDS_LIB mstr_standard
J 0
(-3900 3600);
DISPLAY 0.787234 (-3900 3600);
PAINT MONO (-3900 3600);
DISPLAY INVISIBLE (-3900 3600);
FORCEADD TAP..6
(-3300 3300);
FORCEPROP 3 LASTPIN (-3250 3300) SIG_NAME M_J_CS_N<7>
J 0
(-3240 3310);
DISPLAY 0.659574 (-3240 3310);
PAINT MONO (-3240 3310);
DISPLAY INVISIBLE (-3240 3310);
FORCEPROP 1 LASTPIN (-3250 3300) BN 7
J 0
(-3300 3310);
DISPLAY 0.617021 (-3300 3310);
PAINT PINK (-3300 3310);
FORCEPROP 1 LAST PATH I158
J 0
(-3300 3300);
DISPLAY 0.936170 (-3300 3300);
PAINT GREEN (-3300 3300);
DISPLAY INVISIBLE (-3300 3300);
FORCEPROP 1 LAST HDL_TAP TRUE
J 0
(-2975 3175);
DISPLAY 1.234043 (-2975 3175);
PAINT GREEN (-2975 3175);
DISPLAY INVISIBLE (-2975 3175);
FORCEPROP 1 LAST BODY_TYPE PLUMBING
J 0
(-3300 3250);
DISPLAY 1.234043 (-3300 3250);
PAINT GREEN (-3300 3250);
DISPLAY INVISIBLE (-3300 3250);
FORCEPROP 2 LAST CDS_LIB mstr_standard
J 0
(-3300 3300);
DISPLAY 0.787234 (-3300 3300);
PAINT MONO (-3300 3300);
DISPLAY INVISIBLE (-3300 3300);
FORCEADD TAP..6
(-3300 3250);
FORCEPROP 3 LASTPIN (-3250 3250) SIG_NAME M_J_CS_N<6>
J 0
(-3240 3260);
DISPLAY 0.659574 (-3240 3260);
PAINT MONO (-3240 3260);
DISPLAY INVISIBLE (-3240 3260);
FORCEPROP 1 LASTPIN (-3250 3250) BN 6
J 0
(-3300 3260);
DISPLAY 0.617021 (-3300 3260);
PAINT PINK (-3300 3260);
FORCEPROP 1 LAST PATH I159
J 0
(-3300 3250);
DISPLAY 0.936170 (-3300 3250);
PAINT GREEN (-3300 3250);
DISPLAY INVISIBLE (-3300 3250);
FORCEPROP 1 LAST HDL_TAP TRUE
J 0
(-2975 3125);
DISPLAY 1.234043 (-2975 3125);
PAINT GREEN (-2975 3125);
DISPLAY INVISIBLE (-2975 3125);
FORCEPROP 1 LAST BODY_TYPE PLUMBING
J 0
(-3300 3200);
DISPLAY 1.234043 (-3300 3200);
PAINT GREEN (-3300 3200);
DISPLAY INVISIBLE (-3300 3200);
FORCEPROP 2 LAST CDS_LIB mstr_standard
J 0
(-3300 3250);
DISPLAY 0.787234 (-3300 3250);
PAINT MONO (-3300 3250);
DISPLAY INVISIBLE (-3300 3250);
FORCEADD PVTT_GHJ..1
(-1200 2750);
FORCEPROP 3 LASTPIN (-1200 2700) SIG_NAME PVTT_GHJ\g
J 0
(-1190 2710);
DISPLAY 0.659574 (-1190 2710);
PAINT MONO (-1190 2710);
DISPLAY INVISIBLE (-1190 2710);
FORCEPROP 1 LAST HDL_POWER PVTT_GHJ
J 1
(-1200 2800);
DISPLAY 0.872340 (-1200 2800);
PAINT GREEN (-1200 2800);
DISPLAY INVISIBLE (-1200 2800);
FORCEPROP 2 LAST ROOM DDR4_CH_J
J 0
(-1200 2850);
DISPLAY 0.787234 (-1200 2850);
PAINT ORANGE (-1200 2850);
DISPLAY INVISIBLE (-1200 2850);
FORCEPROP 1 LAST PATH I16
J 0
(-1150 2775);
DISPLAY 0.872340 (-1150 2775);
PAINT AQUA (-1150 2775);
DISPLAY INVISIBLE (-1150 2775);
FORCEPROP 1 LAST BODY_TYPE PLUMBING
J 0
(-1245 2707);
DISPLAY 0.340426 (-1245 2707);
PAINT GREEN (-1245 2707);
DISPLAY INVISIBLE (-1245 2707);
FORCEPROP 2 LAST CDS_LIB mstr_symbols
J 0
(-1200 2750);
PAINT ORANGE (-1200 2750);
DISPLAY INVISIBLE (-1200 2750);
FORCEPROP 2 LAST BOM_COST MEM
J 0
(-1200 2755);
PAINT ORANGE (-1200 2755);
DISPLAY INVISIBLE (-1200 2755);
FORCEPROP 1 LAST VOLTAGE 0.6V
J 0
(-1245 2707);
DISPLAY 0.340426 (-1245 2707);
PAINT SKYBLUE (-1245 2707);
DISPLAY INVISIBLE (-1245 2707);
FORCEADD TAP..6
(-3300 3200);
FORCEPROP 3 LASTPIN (-3250 3200) SIG_NAME M_J_CS_N<5>
J 0
(-3240 3210);
DISPLAY 0.659574 (-3240 3210);
PAINT MONO (-3240 3210);
DISPLAY INVISIBLE (-3240 3210);
FORCEPROP 1 LASTPIN (-3250 3200) BN 5
J 0
(-3300 3210);
DISPLAY 0.617021 (-3300 3210);
PAINT PINK (-3300 3210);
FORCEPROP 1 LAST PATH I160
J 0
(-3300 3200);
DISPLAY 0.936170 (-3300 3200);
PAINT GREEN (-3300 3200);
DISPLAY INVISIBLE (-3300 3200);
FORCEPROP 1 LAST HDL_TAP TRUE
J 0
(-2975 3075);
DISPLAY 1.234043 (-2975 3075);
PAINT GREEN (-2975 3075);
DISPLAY INVISIBLE (-2975 3075);
FORCEPROP 1 LAST BODY_TYPE PLUMBING
J 0
(-3300 3150);
DISPLAY 1.234043 (-3300 3150);
PAINT GREEN (-3300 3150);
DISPLAY INVISIBLE (-3300 3150);
FORCEPROP 2 LAST CDS_LIB mstr_standard
J 0
(-3300 3200);
DISPLAY 0.787234 (-3300 3200);
PAINT MONO (-3300 3200);
DISPLAY INVISIBLE (-3300 3200);
FORCEADD TAP..6
(-3300 3150);
FORCEPROP 3 LASTPIN (-3250 3150) SIG_NAME M_J_CS_N<4>
J 0
(-3240 3160);
DISPLAY 0.659574 (-3240 3160);
PAINT MONO (-3240 3160);
DISPLAY INVISIBLE (-3240 3160);
FORCEPROP 1 LASTPIN (-3250 3150) BN 4
J 0
(-3300 3160);
DISPLAY 0.617021 (-3300 3160);
PAINT PINK (-3300 3160);
FORCEPROP 1 LAST PATH I161
J 0
(-3300 3150);
DISPLAY 0.936170 (-3300 3150);
PAINT GREEN (-3300 3150);
DISPLAY INVISIBLE (-3300 3150);
FORCEPROP 1 LAST HDL_TAP TRUE
J 0
(-2975 3025);
DISPLAY 1.234043 (-2975 3025);
PAINT GREEN (-2975 3025);
DISPLAY INVISIBLE (-2975 3025);
FORCEPROP 1 LAST BODY_TYPE PLUMBING
J 0
(-3300 3100);
DISPLAY 1.234043 (-3300 3100);
PAINT GREEN (-3300 3100);
DISPLAY INVISIBLE (-3300 3100);
FORCEPROP 2 LAST CDS_LIB mstr_standard
J 0
(-3300 3150);
DISPLAY 0.787234 (-3300 3150);
PAINT MONO (-3300 3150);
DISPLAY INVISIBLE (-3300 3150);
FORCEADD TAP..6
(-3300 3050);
FORCEPROP 3 LASTPIN (-3250 3050) SIG_NAME M_J_CKE<3>
J 0
(-3240 3060);
DISPLAY 0.659574 (-3240 3060);
PAINT MONO (-3240 3060);
DISPLAY INVISIBLE (-3240 3060);
FORCEPROP 1 LASTPIN (-3250 3050) BN 3
J 0
(-3300 3060);
DISPLAY 0.617021 (-3300 3060);
PAINT PINK (-3300 3060);
FORCEPROP 1 LAST PATH I162
J 0
(-3300 3050);
DISPLAY 0.936170 (-3300 3050);
PAINT GREEN (-3300 3050);
DISPLAY INVISIBLE (-3300 3050);
FORCEPROP 1 LAST HDL_TAP TRUE
J 0
(-2975 2925);
DISPLAY 1.234043 (-2975 2925);
PAINT GREEN (-2975 2925);
DISPLAY INVISIBLE (-2975 2925);
FORCEPROP 1 LAST BODY_TYPE PLUMBING
J 0
(-3300 3000);
DISPLAY 1.234043 (-3300 3000);
PAINT GREEN (-3300 3000);
DISPLAY INVISIBLE (-3300 3000);
FORCEPROP 2 LAST CDS_LIB mstr_standard
J 0
(-3300 3050);
DISPLAY 0.787234 (-3300 3050);
PAINT MONO (-3300 3050);
DISPLAY INVISIBLE (-3300 3050);
FORCEADD OFFPAGE..1
(-3900 3350);
FORCEPROP 2 LAST $XR1 81 
J 0
(-4211 3350);
DISPLAY 0.638298 (-4211 3350);
PAINT MONO (-4211 3350);
FORCEPROP 2 LAST $XR0 59 
J 0
(-4121 3350);
DISPLAY 0.638298 (-4121 3350);
PAINT MONO (-4121 3350);
FORCEPROP 2 LAST PATH I163
J 0
(-3850 3425);
DISPLAY 0.787234 (-3850 3425);
PAINT MONO (-3850 3425);
DISPLAY INVISIBLE (-3850 3425);
FORCEPROP 1 LAST COMMENT_BODY TRUE
J 0
(-3775 3250);
DISPLAY 0.936170 (-3775 3250);
PAINT GREEN (-3775 3250);
DISPLAY INVISIBLE (-3775 3250);
FORCEPROP 1 LAST OFFPAGE TRUE
J 0
(-3575 3225);
DISPLAY 0.936170 (-3575 3225);
PAINT GREEN (-3575 3225);
DISPLAY INVISIBLE (-3575 3225);
FORCEPROP 2 LAST CDS_LIB mstr_standard
J 0
(-3900 3350);
DISPLAY 0.787234 (-3900 3350);
PAINT MONO (-3900 3350);
DISPLAY INVISIBLE (-3900 3350);
FORCEADD OFFPAGE..1
(-3900 3100);
FORCEPROP 2 LAST $XR1 81 
J 0
(-4211 3100);
DISPLAY 0.638298 (-4211 3100);
PAINT MONO (-4211 3100);
FORCEPROP 2 LAST $XR0 59 
J 0
(-4121 3100);
DISPLAY 0.638298 (-4121 3100);
PAINT MONO (-4121 3100);
FORCEPROP 2 LAST PATH I164
J 0
(-3850 3175);
DISPLAY 0.787234 (-3850 3175);
PAINT MONO (-3850 3175);
DISPLAY INVISIBLE (-3850 3175);
FORCEPROP 1 LAST COMMENT_BODY TRUE
J 0
(-3775 3000);
DISPLAY 0.936170 (-3775 3000);
PAINT GREEN (-3775 3000);
DISPLAY INVISIBLE (-3775 3000);
FORCEPROP 1 LAST OFFPAGE TRUE
J 0
(-3575 2975);
DISPLAY 0.936170 (-3575 2975);
PAINT GREEN (-3575 2975);
DISPLAY INVISIBLE (-3575 2975);
FORCEPROP 2 LAST CDS_LIB mstr_standard
J 0
(-3900 3100);
DISPLAY 0.787234 (-3900 3100);
PAINT MONO (-3900 3100);
DISPLAY INVISIBLE (-3900 3100);
FORCEADD TAP..6
(-3300 3000);
FORCEPROP 3 LASTPIN (-3250 3000) SIG_NAME M_J_CKE<2>
J 0
(-3240 3010);
DISPLAY 0.659574 (-3240 3010);
PAINT MONO (-3240 3010);
DISPLAY INVISIBLE (-3240 3010);
FORCEPROP 1 LASTPIN (-3250 3000) BN 2
J 0
(-3300 3010);
DISPLAY 0.617021 (-3300 3010);
PAINT PINK (-3300 3010);
FORCEPROP 1 LAST PATH I165
J 0
(-3300 3000);
DISPLAY 0.936170 (-3300 3000);
PAINT GREEN (-3300 3000);
DISPLAY INVISIBLE (-3300 3000);
FORCEPROP 1 LAST HDL_TAP TRUE
J 0
(-2975 2875);
DISPLAY 1.234043 (-2975 2875);
PAINT GREEN (-2975 2875);
DISPLAY INVISIBLE (-2975 2875);
FORCEPROP 1 LAST BODY_TYPE PLUMBING
J 0
(-3300 2950);
DISPLAY 1.234043 (-3300 2950);
PAINT GREEN (-3300 2950);
DISPLAY INVISIBLE (-3300 2950);
FORCEPROP 2 LAST CDS_LIB mstr_standard
J 0
(-3300 3000);
DISPLAY 0.787234 (-3300 3000);
PAINT MONO (-3300 3000);
DISPLAY INVISIBLE (-3300 3000);
FORCEADD TAP..6
(-3300 2900);
FORCEPROP 3 LASTPIN (-3250 2900) SIG_NAME M_J_ODT<3>
J 0
(-3240 2910);
DISPLAY 0.659574 (-3240 2910);
PAINT MONO (-3240 2910);
DISPLAY INVISIBLE (-3240 2910);
FORCEPROP 1 LASTPIN (-3250 2900) BN 3
J 0
(-3300 2910);
DISPLAY 0.617021 (-3300 2910);
PAINT PINK (-3300 2910);
FORCEPROP 1 LAST PATH I166
J 0
(-3300 2900);
DISPLAY 0.936170 (-3300 2900);
PAINT GREEN (-3300 2900);
DISPLAY INVISIBLE (-3300 2900);
FORCEPROP 1 LAST HDL_TAP TRUE
J 0
(-2975 2775);
DISPLAY 1.234043 (-2975 2775);
PAINT GREEN (-2975 2775);
DISPLAY INVISIBLE (-2975 2775);
FORCEPROP 1 LAST BODY_TYPE PLUMBING
J 0
(-3300 2850);
DISPLAY 1.234043 (-3300 2850);
PAINT GREEN (-3300 2850);
DISPLAY INVISIBLE (-3300 2850);
FORCEPROP 2 LAST CDS_LIB mstr_standard
J 0
(-3300 2900);
DISPLAY 0.787234 (-3300 2900);
PAINT MONO (-3300 2900);
DISPLAY INVISIBLE (-3300 2900);
FORCEADD OFFPAGE..1
(-3900 2950);
FORCEPROP 2 LAST $XR1 81 
J 0
(-4211 2950);
DISPLAY 0.638298 (-4211 2950);
PAINT MONO (-4211 2950);
FORCEPROP 2 LAST $XR0 59 
J 0
(-4121 2950);
DISPLAY 0.638298 (-4121 2950);
PAINT MONO (-4121 2950);
FORCEPROP 2 LAST PATH I167
J 0
(-3850 3025);
DISPLAY 0.787234 (-3850 3025);
PAINT MONO (-3850 3025);
DISPLAY INVISIBLE (-3850 3025);
FORCEPROP 1 LAST COMMENT_BODY TRUE
J 0
(-3775 2850);
DISPLAY 0.936170 (-3775 2850);
PAINT GREEN (-3775 2850);
DISPLAY INVISIBLE (-3775 2850);
FORCEPROP 1 LAST OFFPAGE TRUE
J 0
(-3575 2825);
DISPLAY 0.936170 (-3575 2825);
PAINT GREEN (-3575 2825);
DISPLAY INVISIBLE (-3575 2825);
FORCEPROP 2 LAST CDS_LIB mstr_standard
J 0
(-3900 2950);
DISPLAY 0.787234 (-3900 2950);
PAINT MONO (-3900 2950);
DISPLAY INVISIBLE (-3900 2950);
FORCEADD TAP..6
(-3300 2850);
FORCEPROP 3 LASTPIN (-3250 2850) SIG_NAME M_J_ODT<2>
J 0
(-3240 2860);
DISPLAY 0.659574 (-3240 2860);
PAINT MONO (-3240 2860);
DISPLAY INVISIBLE (-3240 2860);
FORCEPROP 1 LASTPIN (-3250 2850) BN 2
J 0
(-3300 2860);
DISPLAY 0.617021 (-3300 2860);
PAINT PINK (-3300 2860);
FORCEPROP 1 LAST PATH I168
J 0
(-3300 2850);
DISPLAY 0.936170 (-3300 2850);
PAINT GREEN (-3300 2850);
DISPLAY INVISIBLE (-3300 2850);
FORCEPROP 1 LAST HDL_TAP TRUE
J 0
(-2975 2725);
DISPLAY 1.234043 (-2975 2725);
PAINT GREEN (-2975 2725);
DISPLAY INVISIBLE (-2975 2725);
FORCEPROP 1 LAST BODY_TYPE PLUMBING
J 0
(-3300 2800);
DISPLAY 1.234043 (-3300 2800);
PAINT GREEN (-3300 2800);
DISPLAY INVISIBLE (-3300 2800);
FORCEPROP 2 LAST CDS_LIB mstr_standard
J 0
(-3300 2850);
DISPLAY 0.787234 (-3300 2850);
PAINT MONO (-3300 2850);
DISPLAY INVISIBLE (-3300 2850);
FORCEADD TAP..6
R 2
(850 4600);
FORCEPROP 3 LASTPIN (800 4600) SIG_NAME M_J_DQS_DN<12>
J 0
(810 4610);
DISPLAY 0.659574 (810 4610);
PAINT MONO (810 4610);
DISPLAY INVISIBLE (810 4610);
FORCEPROP 1 LASTPIN (800 4600) BN 12
J 2
(850 4610);
DISPLAY 0.617021 (850 4610);
PAINT PINK (850 4610);
FORCEPROP 1 LAST PATH I17
J 2
(850 4600);
DISPLAY 0.936170 (850 4600);
PAINT GREEN (850 4600);
DISPLAY INVISIBLE (850 4600);
FORCEPROP 1 LAST HDL_TAP TRUE
J 2
(525 4475);
DISPLAY 1.234043 (525 4475);
PAINT GREEN (525 4475);
DISPLAY INVISIBLE (525 4475);
FORCEPROP 1 LAST BODY_TYPE PLUMBING
J 2
(850 4550);
DISPLAY 1.234043 (850 4550);
PAINT GREEN (850 4550);
DISPLAY INVISIBLE (850 4550);
FORCEPROP 2 LAST CDS_LIB mstr_standard
J 0
(850 4600);
DISPLAY 0.787234 (850 4600);
PAINT MONO (850 4600);
DISPLAY INVISIBLE (850 4600);
FORCEADD SCONN288_H44441003..4
(-350 2050);
FORCEPROP 0 LAST BOM_SS NOPOP
J 0
(-601 3103);
DISPLAY 1.021277 (-601 3103);
PAINT BROWN (-601 3103);
DISPLAY BOTH (-601 3103);
FORCEPROP 2 LASTPIN (150 2850) $PN 145
J 0
(160 2860);
DISPLAY 0.617021 (160 2860);
PAINT ORANGE (160 2860);
FORCEPROP 2 LASTPIN (150 2900) $PN 1
J 0
(160 2910);
DISPLAY 0.617021 (160 2910);
PAINT ORANGE (160 2910);
FORCEPROP 2 LASTPIN (-850 1200) $PN 236
J 2
(-860 1210);
DISPLAY 0.617021 (-860 1210);
PAINT ORANGE (-860 1210);
FORCEPROP 2 LASTPIN (-850 1250) $PN 233
J 2
(-860 1260);
DISPLAY 0.617021 (-860 1260);
PAINT ORANGE (-860 1260);
FORCEPROP 2 LASTPIN (-850 1300) $PN 231
J 2
(-860 1310);
DISPLAY 0.617021 (-860 1310);
PAINT ORANGE (-860 1310);
FORCEPROP 2 LASTPIN (-850 1350) $PN 229
J 2
(-860 1360);
DISPLAY 0.617021 (-860 1360);
PAINT ORANGE (-860 1360);
FORCEPROP 2 LASTPIN (-850 1400) $PN 226
J 2
(-860 1410);
DISPLAY 0.617021 (-860 1410);
PAINT ORANGE (-860 1410);
FORCEPROP 2 LASTPIN (-850 1450) $PN 223
J 2
(-860 1460);
DISPLAY 0.617021 (-860 1460);
PAINT ORANGE (-860 1460);
FORCEPROP 2 LASTPIN (-850 1500) $PN 220
J 2
(-860 1510);
DISPLAY 0.617021 (-860 1510);
PAINT ORANGE (-860 1510);
FORCEPROP 2 LASTPIN (-850 1550) $PN 217
J 2
(-860 1560);
DISPLAY 0.617021 (-860 1560);
PAINT ORANGE (-860 1560);
FORCEPROP 2 LASTPIN (-850 1600) $PN 215
J 2
(-860 1610);
DISPLAY 0.617021 (-860 1610);
PAINT ORANGE (-860 1610);
FORCEPROP 2 LASTPIN (-850 1650) $PN 212
J 2
(-860 1660);
DISPLAY 0.617021 (-860 1660);
PAINT ORANGE (-860 1660);
FORCEPROP 2 LASTPIN (-850 1700) $PN 209
J 2
(-860 1710);
DISPLAY 0.617021 (-860 1710);
PAINT ORANGE (-860 1710);
FORCEPROP 2 LASTPIN (-850 1750) $PN 206
J 2
(-860 1760);
DISPLAY 0.617021 (-860 1760);
PAINT ORANGE (-860 1760);
FORCEPROP 2 LASTPIN (-850 1800) $PN 204
J 2
(-860 1810);
DISPLAY 0.617021 (-860 1810);
PAINT ORANGE (-860 1810);
FORCEPROP 2 LASTPIN (-850 1850) $PN 92
J 2
(-860 1860);
DISPLAY 0.617021 (-860 1860);
PAINT ORANGE (-860 1860);
FORCEPROP 2 LASTPIN (-850 1900) $PN 90
J 2
(-860 1910);
DISPLAY 0.617021 (-860 1910);
PAINT ORANGE (-860 1910);
FORCEPROP 2 LASTPIN (-850 1950) $PN 88
J 2
(-860 1960);
DISPLAY 0.617021 (-860 1960);
PAINT ORANGE (-860 1960);
FORCEPROP 2 LASTPIN (-850 2000) $PN 85
J 2
(-860 2010);
DISPLAY 0.617021 (-860 2010);
PAINT ORANGE (-860 2010);
FORCEPROP 2 LASTPIN (-850 2050) $PN 83
J 2
(-860 2060);
DISPLAY 0.617021 (-860 2060);
PAINT ORANGE (-860 2060);
FORCEPROP 2 LASTPIN (-850 2100) $PN 80
J 2
(-860 2110);
DISPLAY 0.617021 (-860 2110);
PAINT ORANGE (-860 2110);
FORCEPROP 2 LASTPIN (-850 2150) $PN 76
J 2
(-860 2160);
DISPLAY 0.617021 (-860 2160);
PAINT ORANGE (-860 2160);
FORCEPROP 2 LASTPIN (-850 2200) $PN 73
J 2
(-860 2210);
DISPLAY 0.617021 (-860 2210);
PAINT ORANGE (-860 2210);
FORCEPROP 2 LASTPIN (-850 2250) $PN 70
J 2
(-860 2260);
DISPLAY 0.617021 (-860 2260);
PAINT ORANGE (-860 2260);
FORCEPROP 2 LASTPIN (-850 2300) $PN 67
J 2
(-860 2310);
DISPLAY 0.617021 (-860 2310);
PAINT ORANGE (-860 2310);
FORCEPROP 2 LASTPIN (-850 2350) $PN 64
J 2
(-860 2360);
DISPLAY 0.617021 (-860 2360);
PAINT ORANGE (-860 2360);
FORCEPROP 2 LASTPIN (-850 2400) $PN 61
J 2
(-860 2410);
DISPLAY 0.617021 (-860 2410);
PAINT ORANGE (-860 2410);
FORCEPROP 2 LASTPIN (-850 2450) $PN 59
J 2
(-860 2460);
DISPLAY 0.617021 (-860 2460);
PAINT ORANGE (-860 2460);
FORCEPROP 2 LASTPIN (-850 2700) $PN 287
J 2
(-860 2710);
DISPLAY 0.617021 (-860 2710);
PAINT ORANGE (-860 2710);
FORCEPROP 2 LASTPIN (-850 2750) $PN 286
J 2
(-860 2760);
DISPLAY 0.617021 (-860 2760);
PAINT ORANGE (-860 2760);
FORCEPROP 2 LASTPIN (-850 2800) $PN 288
J 2
(-860 2810);
DISPLAY 0.617021 (-860 2810);
PAINT ORANGE (-860 2810);
FORCEPROP 2 LASTPIN (-850 2850) $PN 143
J 2
(-860 2860);
DISPLAY 0.617021 (-860 2860);
PAINT ORANGE (-860 2860);
FORCEPROP 2 LASTPIN (-850 2900) $PN 142
J 2
(-860 2910);
DISPLAY 0.617021 (-860 2910);
PAINT ORANGE (-860 2910);
FORCEPROP 2 LASTPIN (-850 2550) $PN 221
J 2
(-860 2560);
DISPLAY 0.617021 (-860 2560);
PAINT ORANGE (-860 2560);
FORCEPROP 2 LASTPIN (-850 2600) $PN 77
J 2
(-860 2610);
DISPLAY 0.617021 (-860 2610);
PAINT ORANGE (-860 2610);
FORCEPROP 1 LAST MATERIAL SCONN
J 0
(-800 3100);
DISPLAY 0.617021 (-800 3100);
PAINT SKYBLUE (-800 3100);
FORCEPROP 1 LAST PART_NUMBER H44441-003
J 0
(-800 1000);
DISPLAY 0.617021 (-800 1000);
PAINT BLUE (-800 1000);
FORCEPROP 1 LAST LOCATION J9U2
J 0
(-800 3150);
DISPLAY 0.617021 (-800 3150);
PAINT AQUA (-800 3150);
FORCEPROP 2 LAST ROOM DDR4_CH_J
J 0
(-350 2050);
PAINT ORANGE (-350 2050);
DISPLAY INVISIBLE (-350 2050);
FORCEPROP 1 LAST PATH I171
J 0
(-350 3100);
PAINT GREEN (-350 3100);
DISPLAY INVISIBLE (-350 3100);
FORCEPROP 2 LAST CDS_LOCATION J9U2
J 0
(-800 3150);
DISPLAY 0.617021 (-800 3150);
PAINT AQUA (-800 3150);
DISPLAY INVISIBLE (-800 3150);
FORCEPROP 2 LAST SEC 4
J 0
(-800 3200);
DISPLAY 0.680851 (-800 3200);
PAINT MONO (-800 3200);
DISPLAY INVISIBLE (-800 3200);
FORCEPROP 2 LAST SEC_TYPE PIP
J 0
(-800 3200);
DISPLAY 1.021277 (-800 3200);
PAINT ORANGE (-800 3200);
DISPLAY INVISIBLE (-800 3200);
FORCEPROP 2 LAST CDS_LIB mstr_sconn
J 0
(-350 2050);
PAINT ORANGE (-350 2050);
DISPLAY INVISIBLE (-350 2050);
FORCEPROP 2 LAST BOM_COST MEM
J 0
(-350 2050);
PAINT ORANGE (-350 2050);
DISPLAY INVISIBLE (-350 2050);
FORCEPROP 1 LAST PACK_TYPE PIP
J 0
(-800 3200);
PAINT SKYBLUE (-800 3200);
DISPLAY INVISIBLE (-800 3200);
FORCEADD GND..1
R 2
(2450 1050);
FORCEPROP 3 LASTPIN (2450 1100) SIG_NAME GND\g
J 0
(2460 1110);
DISPLAY 0.659574 (2460 1110);
PAINT MONO (2460 1110);
DISPLAY INVISIBLE (2460 1110);
FORCEPROP 1 LAST HDL_POWER GND
J 2
(2450 1200);
DISPLAY 0.553191 (2450 1200);
PAINT GREEN (2450 1200);
DISPLAY INVISIBLE (2450 1200);
FORCEPROP 2 LAST ROOM DDR4_CH_J
J 0
(2450 1055);
PAINT ORANGE (2450 1055);
DISPLAY INVISIBLE (2450 1055);
FORCEPROP 1 LAST PATH I172
J 2
(2375 1050);
DISPLAY 1.404255 (2375 1050);
PAINT GREEN (2375 1050);
DISPLAY INVISIBLE (2375 1050);
FORCEPROP 1 LAST BODY_TYPE PLUMBING
J 2
(2495 1007);
DISPLAY 0.340426 (2495 1007);
PAINT GREEN (2495 1007);
DISPLAY INVISIBLE (2495 1007);
FORCEPROP 2 LAST BOM_COST MEM
J 0
(2450 1055);
PAINT ORANGE (2450 1055);
DISPLAY INVISIBLE (2450 1055);
FORCEPROP 2 LAST CDS_LIB mstr_symbols
J 0
(2450 1050);
DISPLAY 0.787234 (2450 1050);
PAINT MONO (2450 1050);
DISPLAY INVISIBLE (2450 1050);
FORCEPROP 1 LAST SIZE 1B
J 2
(2375 1000);
DISPLAY 1.170213 (2375 1000);
PAINT GREEN (2375 1000);
DISPLAY INVISIBLE (2375 1000);
FORCEPROP 1 LAST VOLTAGE 0
J 0
(2450 1050);
PAINT SKYBLUE (2450 1050);
DISPLAY INVISIBLE (2450 1050);
FORCEADD OFFPAGE..1
(-3900 1750);
FORCEPROP 2 LAST $XR5 81 
J 0
(-4631 1750);
DISPLAY 0.638298 (-4631 1750);
PAINT MONO (-4631 1750);
FORCEPROP 2 LAST $XR4 80 
J 0
(-4541 1750);
DISPLAY 0.638298 (-4541 1750);
PAINT MONO (-4541 1750);
FORCEPROP 2 LAST $XR3 79 
J 0
(-4451 1750);
DISPLAY 0.638298 (-4451 1750);
PAINT MONO (-4451 1750);
FORCEPROP 2 LAST $XR2 78 
J 0
(-4361 1750);
DISPLAY 0.638298 (-4361 1750);
PAINT MONO (-4361 1750);
FORCEPROP 2 LAST $XR1 77 
J 0
(-4271 1750);
DISPLAY 0.638298 (-4271 1750);
PAINT MONO (-4271 1750);
FORCEPROP 2 LAST $XR0 99 
J 0
(-4181 1750);
DISPLAY 0.638298 (-4181 1750);
PAINT MONO (-4181 1750);
FORCEPROP 2 LAST PATH I173
J 0
(-4175 1800);
DISPLAY 0.787234 (-4175 1800);
PAINT ORANGE (-4175 1800);
DISPLAY INVISIBLE (-4175 1800);
FORCEPROP 1 LAST COMMENT_BODY TRUE
J 0
(-3775 1650);
DISPLAY 0.936170 (-3775 1650);
PAINT GREEN (-3775 1650);
DISPLAY INVISIBLE (-3775 1650);
FORCEPROP 1 LAST OFFPAGE TRUE
J 0
(-3575 1625);
DISPLAY 0.936170 (-3575 1625);
PAINT GREEN (-3575 1625);
DISPLAY INVISIBLE (-3575 1625);
FORCEPROP 2 LAST CDS_LIB mstr_standard
J 0
(-3900 1750);
DISPLAY 0.787234 (-3900 1750);
PAINT MONO (-3900 1750);
DISPLAY INVISIBLE (-3900 1750);
FORCEADD OFFPAGE..6
(-3900 1800);
FORCEPROP 2 LASTPIN (-3850 1800) SIG_NAME SMB_DDR_GHJ_VPP_SDA
J 0
(-3810 1810);
DISPLAY 0.617021 (-3810 1810);
PAINT ORANGE (-3810 1810);
FORCEPROP 2 LAST $XR5 99 
J 0
(-4629 1800);
DISPLAY 0.638298 (-4629 1800);
PAINT MONO (-4629 1800);
FORCEPROP 2 LAST $XR4 81 
J 0
(-4539 1800);
DISPLAY 0.638298 (-4539 1800);
PAINT MONO (-4539 1800);
FORCEPROP 2 LAST $XR3 80 
J 0
(-4449 1800);
DISPLAY 0.638298 (-4449 1800);
PAINT MONO (-4449 1800);
FORCEPROP 2 LAST $XR2 79 
J 0
(-4359 1800);
DISPLAY 0.638298 (-4359 1800);
PAINT MONO (-4359 1800);
FORCEPROP 2 LAST $XR1 78 
J 0
(-4269 1800);
DISPLAY 0.638298 (-4269 1800);
PAINT MONO (-4269 1800);
FORCEPROP 2 LAST $XR0 77 
J 0
(-4179 1800);
DISPLAY 0.638298 (-4179 1800);
PAINT MONO (-4179 1800);
FORCEPROP 2 LAST PATH I174
J 0
(-4225 1850);
DISPLAY 0.787234 (-4225 1850);
PAINT ORANGE (-4225 1850);
DISPLAY INVISIBLE (-4225 1850);
FORCEPROP 1 LAST COMMENT_BODY TRUE
J 0
(-3800 1725);
DISPLAY 0.936170 (-3800 1725);
PAINT GREEN (-3800 1725);
DISPLAY INVISIBLE (-3800 1725);
FORCEPROP 1 LAST OFFPAGE TRUE
J 0
(-3575 1675);
DISPLAY 0.936170 (-3575 1675);
PAINT GREEN (-3575 1675);
DISPLAY INVISIBLE (-3575 1675);
FORCEPROP 2 LAST CDS_LIB mstr_standard
J 0
(-3900 1800);
DISPLAY 0.787234 (-3900 1800);
PAINT MONO (-3900 1800);
DISPLAY INVISIBLE (-3900 1800);
FORCEADD OFFPAGE..1
(-4650 1650);
FORCEPROP 2 LAST $XR1 81 
J 0
(-4992 1650);
DISPLAY 0.638298 (-4992 1650);
PAINT MONO (-4992 1650);
FORCEPROP 2 LAST $XR0 100 
J 0
(-4902 1650);
DISPLAY 0.638298 (-4902 1650);
PAINT MONO (-4902 1650);
FORCEPROP 2 LAST PATH I175
J 0
(-4900 1700);
DISPLAY 0.787234 (-4900 1700);
PAINT ORANGE (-4900 1700);
DISPLAY INVISIBLE (-4900 1700);
FORCEPROP 1 LAST COMMENT_BODY TRUE
J 0
(-4525 1550);
DISPLAY 0.936170 (-4525 1550);
PAINT GREEN (-4525 1550);
DISPLAY INVISIBLE (-4525 1550);
FORCEPROP 1 LAST OFFPAGE TRUE
J 0
(-4325 1525);
DISPLAY 0.936170 (-4325 1525);
PAINT GREEN (-4325 1525);
DISPLAY INVISIBLE (-4325 1525);
FORCEPROP 2 LAST CDS_LIB mstr_standard
J 0
(-4650 1650);
DISPLAY 0.787234 (-4650 1650);
PAINT MONO (-4650 1650);
DISPLAY INVISIBLE (-4650 1650);
FORCEADD OFFPAGE..5
(-4325 2450);
FORCEPROP 2 LAST $XR23 94 
J 0
(-5029 2486);
DISPLAY 0.638298 (-5029 2486);
PAINT MONO (-5029 2486);
FORCEPROP 2 LAST $XR22 88 
J 0
(-4939 2486);
DISPLAY 0.638298 (-4939 2486);
PAINT MONO (-4939 2486);
FORCEPROP 2 LAST $XR21 87 
J 0
(-4849 2486);
DISPLAY 0.638298 (-4849 2486);
PAINT MONO (-4849 2486);
FORCEPROP 2 LAST $XR20 86 
J 0
(-4759 2486);
DISPLAY 0.638298 (-4759 2486);
PAINT MONO (-4759 2486);
FORCEPROP 2 LAST $XR19 85 
J 0
(-4669 2486);
DISPLAY 0.638298 (-4669 2486);
PAINT MONO (-4669 2486);
FORCEPROP 2 LAST $XR18 84 
J 0
(-4579 2486);
DISPLAY 0.638298 (-4579 2486);
PAINT MONO (-4579 2486);
FORCEPROP 2 LAST $XR17 83 
J 0
(-5299 2414);
DISPLAY 0.638298 (-5299 2414);
PAINT MONO (-5299 2414);
FORCEPROP 2 LAST $XR16 81 
J 0
(-5209 2414);
DISPLAY 0.638298 (-5209 2414);
PAINT MONO (-5209 2414);
FORCEPROP 2 LAST $XR15 80 
J 0
(-5119 2414);
DISPLAY 0.638298 (-5119 2414);
PAINT MONO (-5119 2414);
FORCEPROP 2 LAST $XR14 79 
J 0
(-5029 2414);
DISPLAY 0.638298 (-5029 2414);
PAINT MONO (-5029 2414);
FORCEPROP 2 LAST $XR13 78 
J 0
(-4939 2414);
DISPLAY 0.638298 (-4939 2414);
PAINT MONO (-4939 2414);
FORCEPROP 2 LAST $XR12 77 
J 0
(-4849 2414);
DISPLAY 0.638298 (-4849 2414);
PAINT MONO (-4849 2414);
FORCEPROP 2 LAST $XR11 54 
J 0
(-4759 2414);
DISPLAY 0.638298 (-4759 2414);
PAINT MONO (-4759 2414);
FORCEPROP 2 LAST $XR10 53 
J 0
(-4669 2414);
DISPLAY 0.638298 (-4669 2414);
PAINT MONO (-4669 2414);
FORCEPROP 2 LAST $XR9 52 
J 0
(-4579 2414);
DISPLAY 0.638298 (-4579 2414);
PAINT MONO (-4579 2414);
FORCEPROP 2 LAST $XR8 51 
J 0
(-5299 2450);
DISPLAY 0.638298 (-5299 2450);
PAINT MONO (-5299 2450);
FORCEPROP 2 LAST $XR7 50 
J 0
(-5209 2450);
DISPLAY 0.638298 (-5209 2450);
PAINT MONO (-5209 2450);
FORCEPROP 2 LAST $XR6 49 
J 0
(-5119 2450);
DISPLAY 0.638298 (-5119 2450);
PAINT MONO (-5119 2450);
FORCEPROP 2 LAST $XR5 48 
J 0
(-5029 2450);
DISPLAY 0.638298 (-5029 2450);
PAINT MONO (-5029 2450);
FORCEPROP 2 LAST $XR4 47 
J 0
(-4939 2450);
DISPLAY 0.638298 (-4939 2450);
PAINT MONO (-4939 2450);
FORCEPROP 2 LAST $XR3 46 
J 0
(-4849 2450);
DISPLAY 0.638298 (-4849 2450);
PAINT MONO (-4849 2450);
FORCEPROP 2 LAST $XR2 45 
J 0
(-4759 2450);
DISPLAY 0.638298 (-4759 2450);
PAINT MONO (-4759 2450);
FORCEPROP 2 LAST $XR1 44 
J 0
(-4669 2450);
DISPLAY 0.638298 (-4669 2450);
PAINT MONO (-4669 2450);
FORCEPROP 2 LAST $XR0 43 
J 0
(-4579 2450);
DISPLAY 0.638298 (-4579 2450);
PAINT MONO (-4579 2450);
FORCEPROP 2 LAST PATH I178
J 0
(-4275 2525);
DISPLAY 0.787234 (-4275 2525);
PAINT ORANGE (-4275 2525);
DISPLAY INVISIBLE (-4275 2525);
FORCEPROP 1 LAST COMMENT_BODY TRUE
J 0
(-4225 2375);
DISPLAY 1.404255 (-4225 2375);
PAINT GREEN (-4225 2375);
DISPLAY INVISIBLE (-4225 2375);
FORCEPROP 1 LAST OFFPAGE TRUE
J 0
(-4000 2325);
DISPLAY 1.404255 (-4000 2325);
PAINT GREEN (-4000 2325);
DISPLAY INVISIBLE (-4000 2325);
FORCEPROP 2 LAST CDS_LIB mstr_standard
J 0
(-4325 2450);
DISPLAY 0.787234 (-4325 2450);
PAINT MONO (-4325 2450);
DISPLAY INVISIBLE (-4325 2450);
FORCEADD GND..1
(-4500 1150);
FORCEPROP 3 LASTPIN (-4500 1200) SIG_NAME GND\g
J 0
(-4490 1210);
DISPLAY 0.659574 (-4490 1210);
PAINT MONO (-4490 1210);
DISPLAY INVISIBLE (-4490 1210);
FORCEPROP 1 LAST HDL_POWER GND
J 0
(-4500 1300);
DISPLAY 1.404255 (-4500 1300);
PAINT GREEN (-4500 1300);
DISPLAY INVISIBLE (-4500 1300);
FORCEPROP 2 LAST ROOM DDR4_CH_J
J 0
(-4500 1155);
PAINT ORANGE (-4500 1155);
DISPLAY INVISIBLE (-4500 1155);
FORCEPROP 1 LAST PATH I179
J 0
(-4425 1150);
DISPLAY 1.404255 (-4425 1150);
PAINT GREEN (-4425 1150);
DISPLAY INVISIBLE (-4425 1150);
FORCEPROP 1 LAST BODY_TYPE PLUMBING
J 0
(-4545 1107);
DISPLAY 0.340426 (-4545 1107);
PAINT GREEN (-4545 1107);
DISPLAY INVISIBLE (-4545 1107);
FORCEPROP 2 LAST BOM_COST MEM
J 0
(-4500 1155);
PAINT ORANGE (-4500 1155);
DISPLAY INVISIBLE (-4500 1155);
FORCEPROP 1 LAST SIZE 1B
J 0
(-4425 1100);
DISPLAY 1.787234 (-4425 1100);
PAINT GREEN (-4425 1100);
DISPLAY INVISIBLE (-4425 1100);
FORCEPROP 2 LAST CDS_LIB mstr_symbols
J 0
(-4500 1150);
PAINT ORANGE (-4500 1150);
DISPLAY INVISIBLE (-4500 1150);
FORCEPROP 1 LAST VOLTAGE 0
J 0
(-4500 1150);
PAINT SKYBLUE (-4500 1150);
DISPLAY INVISIBLE (-4500 1150);
FORCEADD TAP..6
R 2
(850 4500);
FORCEPROP 3 LASTPIN (800 4500) SIG_NAME M_J_DQS_DN<11>
J 0
(810 4510);
DISPLAY 0.659574 (810 4510);
PAINT MONO (810 4510);
DISPLAY INVISIBLE (810 4510);
FORCEPROP 1 LASTPIN (800 4500) BN 11
J 2
(850 4510);
DISPLAY 0.617021 (850 4510);
PAINT PINK (850 4510);
FORCEPROP 1 LAST PATH I18
J 2
(850 4500);
DISPLAY 0.936170 (850 4500);
PAINT GREEN (850 4500);
DISPLAY INVISIBLE (850 4500);
FORCEPROP 1 LAST HDL_TAP TRUE
J 2
(525 4375);
DISPLAY 1.234043 (525 4375);
PAINT GREEN (525 4375);
DISPLAY INVISIBLE (525 4375);
FORCEPROP 1 LAST BODY_TYPE PLUMBING
J 2
(850 4450);
DISPLAY 1.234043 (850 4450);
PAINT GREEN (850 4450);
DISPLAY INVISIBLE (850 4450);
FORCEPROP 2 LAST CDS_LIB mstr_standard
J 0
(850 4500);
DISPLAY 0.787234 (850 4500);
PAINT MONO (850 4500);
DISPLAY INVISIBLE (850 4500);
FORCEADD CAP_A..1
R 2
(-4500 1450);
FORCEPROP 1 LAST MATERIAL X7R
J 2
(-4550 1350);
DISPLAY 0.617021 (-4550 1350);
PAINT SKYBLUE (-4550 1350);
FORCEPROP 1 LAST VOLTAGE 25V
J 2
(-4550 1450);
DISPLAY 0.617021 (-4550 1450);
PAINT SKYBLUE (-4550 1450);
FORCEPROP 1 LAST PACK_TYPE 0402V
J 2
(-4550 1250);
DISPLAY 0.617021 (-4550 1250);
PAINT SKYBLUE (-4550 1250);
FORCEPROP 1 LAST TOLERANCE 10%
J 2
(-4550 1400);
DISPLAY 0.617021 (-4550 1400);
PAINT SKYBLUE (-4550 1400);
FORCEPROP 1 LAST VALUE 0.01UF
J 2
(-4550 1500);
DISPLAY 0.617021 (-4550 1500);
PAINT SKYBLUE (-4550 1500);
FORCEPROP 1 LAST PART_NUMBER A36096-045
J 2
(-4550 1300);
DISPLAY 0.617021 (-4550 1300);
PAINT BLUE (-4550 1300);
FORCEPROP 1 LAST LOCATION C1G19
J 2
(-4550 1550);
DISPLAY 0.617021 (-4550 1550);
PAINT AQUA (-4550 1550);
FORCEPROP 1 LASTPIN (-4500 1350) $PN 2
J 2
(-4510 1330);
DISPLAY 0.787234 (-4510 1330);
PAINT ORANGE (-4510 1330);
DISPLAY INVISIBLE (-4510 1330);
FORCEPROP 1 LASTPIN (-4500 1550) $PN 1
J 2
(-4510 1530);
DISPLAY 0.787234 (-4510 1530);
PAINT ORANGE (-4510 1530);
DISPLAY INVISIBLE (-4510 1530);
FORCEPROP 2 LAST ROOM DDR4_CH_J
J 0
(-4500 1450);
PAINT ORANGE (-4500 1450);
DISPLAY INVISIBLE (-4500 1450);
FORCEPROP 1 LAST PATH I180
J 2
(-4550 1600);
DISPLAY 0.978723 (-4550 1600);
PAINT WHITE (-4550 1600);
DISPLAY INVISIBLE (-4550 1600);
FORCEPROP 2 LAST $SEC 1
J 0
(-4550 1650);
PAINT MONO (-4550 1650);
DISPLAY INVISIBLE (-4550 1650);
FORCEPROP 2 LAST CDS_SEC 1
J 2
(-4550 1650);
PAINT MONO (-4550 1650);
DISPLAY INVISIBLE (-4550 1650);
FORCEPROP 2 LAST CDS_LIB dev_discrete
J 0
(-4500 1450);
PAINT ORANGE (-4500 1450);
DISPLAY INVISIBLE (-4500 1450);
FORCEPROP 2 LAST BOM_COST MEM
J 0
(-4500 1450);
PAINT ORANGE (-4500 1450);
DISPLAY INVISIBLE (-4500 1450);
FORCEPROP 2 LAST CDS_LOCATION C1G19
J 2
(-4550 1550);
DISPLAY 0.617021 (-4550 1550);
PAINT AQUA (-4550 1550);
DISPLAY INVISIBLE (-4550 1550);
FORCEADD PVPP_GHJ..1
(-1050 3025);
FORCEPROP 3 LASTPIN (-1050 2975) SIG_NAME PVPP_GHJ\g
J 0
(-1040 2985);
DISPLAY 0.659574 (-1040 2985);
PAINT MONO (-1040 2985);
DISPLAY INVISIBLE (-1040 2985);
FORCEPROP 1 LAST HDL_POWER PVPP_GHJ
J 1
(-1050 3075);
DISPLAY 0.872340 (-1050 3075);
PAINT GREEN (-1050 3075);
DISPLAY INVISIBLE (-1050 3075);
FORCEPROP 2 LAST ROOM DDR4_CH_K
J 0
(-1050 3125);
PAINT ORANGE (-1050 3125);
DISPLAY INVISIBLE (-1050 3125);
FORCEPROP 1 LAST PATH I181
J 0
(-1000 3050);
DISPLAY 0.872340 (-1000 3050);
PAINT AQUA (-1000 3050);
DISPLAY INVISIBLE (-1000 3050);
FORCEPROP 1 LAST BODY_TYPE PLUMBING
J 0
(-1095 2982);
DISPLAY 0.340426 (-1095 2982);
PAINT GREEN (-1095 2982);
DISPLAY INVISIBLE (-1095 2982);
FORCEPROP 2 LAST CDS_LIB mstr_symbols
J 0
(-1050 3025);
PAINT ORANGE (-1050 3025);
DISPLAY INVISIBLE (-1050 3025);
FORCEPROP 0 LAST BOM_COST MEM
J 0
(-1050 3125);
PAINT ORANGE (-1050 3125);
DISPLAY INVISIBLE (-1050 3125);
FORCEPROP 1 LAST VOLTAGE 2.5V
J 0
(-1095 2982);
DISPLAY 0.340426 (-1095 2982);
PAINT SKYBLUE (-1095 2982);
DISPLAY INVISIBLE (-1095 2982);
FORCEADD PVPP_GHJ..1
(-5200 2150);
FORCEPROP 3 LASTPIN (-5200 2100) SIG_NAME PVPP_GHJ\g
J 0
(-5190 2110);
DISPLAY 0.659574 (-5190 2110);
PAINT MONO (-5190 2110);
DISPLAY INVISIBLE (-5190 2110);
FORCEPROP 1 LAST HDL_POWER PVPP_GHJ
J 1
(-5200 2200);
DISPLAY 0.872340 (-5200 2200);
PAINT GREEN (-5200 2200);
DISPLAY INVISIBLE (-5200 2200);
FORCEPROP 2 LAST ROOM DDR4_CH_J
J 0
(-5200 2250);
PAINT ORANGE (-5200 2250);
DISPLAY INVISIBLE (-5200 2250);
FORCEPROP 1 LAST PATH I182
J 0
(-5150 2175);
DISPLAY 0.872340 (-5150 2175);
PAINT AQUA (-5150 2175);
DISPLAY INVISIBLE (-5150 2175);
FORCEPROP 1 LAST BODY_TYPE PLUMBING
J 0
(-5245 2107);
DISPLAY 0.340426 (-5245 2107);
PAINT GREEN (-5245 2107);
DISPLAY INVISIBLE (-5245 2107);
FORCEPROP 2 LAST CDS_LIB mstr_symbols
J 0
(-5200 2150);
PAINT ORANGE (-5200 2150);
DISPLAY INVISIBLE (-5200 2150);
FORCEPROP 0 LAST BOM_COST MEM
J 0
(-5200 2250);
PAINT ORANGE (-5200 2250);
DISPLAY INVISIBLE (-5200 2250);
FORCEPROP 1 LAST VOLTAGE 2.5V
J 0
(-5245 2107);
DISPLAY 0.340426 (-5245 2107);
PAINT SKYBLUE (-5245 2107);
DISPLAY INVISIBLE (-5245 2107);
FORCEADD OFFPAGE..1
(-3900 1350);
FORCEPROP 2 LAST $XR5 81 
J 0
(-4121 1314);
DISPLAY 0.638298 (-4121 1314);
PAINT MONO (-4121 1314);
FORCEPROP 2 LAST $XR4 80 
J 0
(-4481 1350);
DISPLAY 0.638298 (-4481 1350);
PAINT MONO (-4481 1350);
FORCEPROP 2 LAST $XR3 79 
J 0
(-4391 1350);
DISPLAY 0.638298 (-4391 1350);
PAINT MONO (-4391 1350);
FORCEPROP 2 LAST $XR2 78 
J 0
(-4301 1350);
DISPLAY 0.638298 (-4301 1350);
PAINT MONO (-4301 1350);
FORCEPROP 2 LAST $XR1 77 
J 0
(-4211 1350);
DISPLAY 0.638298 (-4211 1350);
PAINT MONO (-4211 1350);
FORCEPROP 2 LAST $XR0 89 
J 0
(-4121 1350);
DISPLAY 0.638298 (-4121 1350);
PAINT MONO (-4121 1350);
FORCEPROP 2 LAST PATH I183
J 0
(-3850 1425);
PAINT ORANGE (-3850 1425);
DISPLAY INVISIBLE (-3850 1425);
FORCEPROP 1 LAST COMMENT_BODY TRUE
J 0
(-3775 1250);
DISPLAY 0.936170 (-3775 1250);
PAINT GREEN (-3775 1250);
DISPLAY INVISIBLE (-3775 1250);
FORCEPROP 1 LAST OFFPAGE TRUE
J 0
(-3575 1225);
DISPLAY 0.936170 (-3575 1225);
PAINT GREEN (-3575 1225);
DISPLAY INVISIBLE (-3575 1225);
FORCEPROP 2 LAST CDS_LIB mstr_standard
J 0
(-3900 1350);
PAINT ORANGE (-3900 1350);
DISPLAY INVISIBLE (-3900 1350);
FORCEADD SCONN288_H44441003..1
(-2500 3150);
FORCEPROP 1 LAST MATERIAL SCONN
J 0
(-2950 5000);
DISPLAY 0.617021 (-2950 5000);
PAINT SKYBLUE (-2950 5000);
FORCEPROP 0 LAST BOM_SS NOPOP
J 0
(-2751 4978);
DISPLAY 1.021277 (-2751 4978);
PAINT BROWN (-2751 4978);
DISPLAY BOTH (-2751 4978);
FORCEPROP 2 LASTPIN (-2000 4750) $PN 135
J 0
(-1990 4760);
DISPLAY 0.617021 (-1990 4760);
PAINT ORANGE (-1990 4760);
FORCEPROP 2 LASTPIN (-2000 4700) $PN 273
J 0
(-1990 4710);
DISPLAY 0.617021 (-1990 4710);
PAINT ORANGE (-1990 4710);
FORCEPROP 2 LASTPIN (-2000 4450) $PN 130
J 0
(-1990 4460);
DISPLAY 0.617021 (-1990 4460);
PAINT ORANGE (-1990 4460);
FORCEPROP 2 LASTPIN (-2000 4400) $PN 269
J 0
(-1990 4410);
DISPLAY 0.617021 (-1990 4410);
PAINT ORANGE (-1990 4410);
FORCEPROP 2 LASTPIN (-2000 3400) $PN 249
J 0
(-1990 3410);
DISPLAY 0.617021 (-1990 3410);
PAINT ORANGE (-1990 3410);
FORCEPROP 2 LASTPIN (-2000 4550) $PN 137
J 0
(-1990 4560);
DISPLAY 0.617021 (-1990 4560);
PAINT ORANGE (-1990 4560);
FORCEPROP 2 LASTPIN (-3000 3950) $PN 79
J 2
(-3010 3960);
DISPLAY 0.617021 (-3010 3960);
PAINT ORANGE (-3010 3960);
FORCEPROP 2 LASTPIN (-3000 4000) $PN 72
J 2
(-3010 4010);
DISPLAY 0.617021 (-3010 4010);
PAINT ORANGE (-3010 4010);
FORCEPROP 2 LASTPIN (-3000 4050) $PN 216
J 2
(-3010 4060);
DISPLAY 0.617021 (-3010 4060);
PAINT ORANGE (-3010 4060);
FORCEPROP 2 LASTPIN (-3000 4100) $PN 71
J 2
(-3010 4110);
DISPLAY 0.617021 (-3010 4110);
PAINT ORANGE (-3010 4110);
FORCEPROP 2 LASTPIN (-3000 4150) $PN 214
J 2
(-3010 4160);
DISPLAY 0.617021 (-3010 4160);
PAINT ORANGE (-3010 4160);
FORCEPROP 2 LASTPIN (-3000 4200) $PN 213
J 2
(-3010 4210);
DISPLAY 0.617021 (-3010 4210);
PAINT ORANGE (-3010 4210);
FORCEPROP 2 LASTPIN (-3000 4250) $PN 69
J 2
(-3010 4260);
DISPLAY 0.617021 (-3010 4260);
PAINT ORANGE (-3010 4260);
FORCEPROP 2 LASTPIN (-3000 4300) $PN 211
J 2
(-3010 4310);
DISPLAY 0.617021 (-3010 4310);
PAINT ORANGE (-3010 4310);
FORCEPROP 2 LASTPIN (-3000 4350) $PN 68
J 2
(-3010 4360);
DISPLAY 0.617021 (-3010 4360);
PAINT ORANGE (-3010 4360);
FORCEPROP 2 LASTPIN (-3000 4400) $PN 66
J 2
(-3010 4410);
DISPLAY 0.617021 (-3010 4410);
PAINT ORANGE (-3010 4410);
FORCEPROP 2 LASTPIN (-3000 4450) $PN 225
J 2
(-3010 4460);
DISPLAY 0.617021 (-3010 4460);
PAINT ORANGE (-3010 4460);
FORCEPROP 2 LASTPIN (-3000 4500) $PN 210
J 2
(-3010 4510);
DISPLAY 0.617021 (-3010 4510);
PAINT ORANGE (-3010 4510);
FORCEPROP 2 LASTPIN (-3000 4550) $PN 65
J 2
(-3010 4560);
DISPLAY 0.617021 (-3010 4560);
PAINT ORANGE (-3010 4560);
FORCEPROP 2 LASTPIN (-3000 4600) $PN 232
J 2
(-3010 4610);
DISPLAY 0.617021 (-3010 4610);
PAINT ORANGE (-3010 4610);
FORCEPROP 2 LASTPIN (-3000 4650) $PN 228
J 2
(-3010 4660);
DISPLAY 0.617021 (-3010 4660);
PAINT ORANGE (-3010 4660);
FORCEPROP 2 LASTPIN (-3000 4700) $PN 86
J 2
(-3010 4710);
DISPLAY 0.617021 (-3010 4710);
PAINT ORANGE (-3010 4710);
FORCEPROP 2 LASTPIN (-3000 4750) $PN 82
J 2
(-3010 4760);
DISPLAY 0.617021 (-3010 4760);
PAINT ORANGE (-3010 4760);
FORCEPROP 2 LASTPIN (-3000 4800) $PN 234
J 2
(-3010 4810);
DISPLAY 0.617021 (-3010 4810);
PAINT ORANGE (-3010 4810);
FORCEPROP 2 LASTPIN (-3000 2100) $PN 62
J 2
(-3010 2110);
DISPLAY 0.617021 (-3010 2110);
PAINT ORANGE (-3010 2110);
FORCEPROP 2 LASTPIN (-3000 2150) $PN 208
J 2
(-3010 2160);
DISPLAY 0.617021 (-3010 2160);
PAINT ORANGE (-3010 2160);
FORCEPROP 2 LASTPIN (-3000 3800) $PN 81
J 2
(-3010 3810);
DISPLAY 0.617021 (-3010 3810);
PAINT ORANGE (-3010 3810);
FORCEPROP 2 LASTPIN (-3000 3850) $PN 224
J 2
(-3010 3860);
DISPLAY 0.617021 (-3010 3860);
PAINT ORANGE (-3010 3860);
FORCEPROP 2 LASTPIN (-3000 3700) $PN 63
J 2
(-3010 3710);
DISPLAY 0.617021 (-3010 3710);
PAINT ORANGE (-3010 3710);
FORCEPROP 2 LASTPIN (-3000 3750) $PN 207
J 2
(-3010 3760);
DISPLAY 0.617021 (-3010 3760);
PAINT ORANGE (-3010 3760);
FORCEPROP 2 LASTPIN (-3000 3350) $PN 235
J 2
(-3010 3360);
DISPLAY 0.617021 (-3010 3360);
PAINT ORANGE (-3010 3360);
FORCEPROP 2 LASTPIN (-3000 2400) $PN 49
J 2
(-3010 2410);
DISPLAY 0.617021 (-3010 2410);
PAINT ORANGE (-3010 2410);
FORCEPROP 2 LASTPIN (-3000 2450) $PN 194
J 2
(-3010 2460);
DISPLAY 0.617021 (-3010 2460);
PAINT ORANGE (-3010 2460);
FORCEPROP 2 LASTPIN (-3000 2500) $PN 56
J 2
(-3010 2510);
DISPLAY 0.617021 (-3010 2510);
PAINT ORANGE (-3010 2510);
FORCEPROP 2 LASTPIN (-3000 2550) $PN 201
J 2
(-3010 2560);
DISPLAY 0.617021 (-3010 2560);
PAINT ORANGE (-3010 2560);
FORCEPROP 2 LASTPIN (-3000 2600) $PN 47
J 2
(-3010 2610);
DISPLAY 0.617021 (-3010 2610);
PAINT ORANGE (-3010 2610);
FORCEPROP 2 LASTPIN (-3000 2650) $PN 192
J 2
(-3010 2660);
DISPLAY 0.617021 (-3010 2660);
PAINT ORANGE (-3010 2660);
FORCEPROP 2 LASTPIN (-3000 2700) $PN 54
J 2
(-3010 2710);
DISPLAY 0.617021 (-3010 2710);
PAINT ORANGE (-3010 2710);
FORCEPROP 2 LASTPIN (-3000 2750) $PN 199
J 2
(-3010 2760);
DISPLAY 0.617021 (-3010 2760);
PAINT ORANGE (-3010 2760);
FORCEPROP 2 LASTPIN (-3000 3450) $PN 75
J 2
(-3010 3460);
DISPLAY 0.617021 (-3010 3460);
PAINT ORANGE (-3010 3460);
FORCEPROP 2 LASTPIN (-3000 3500) $PN 74
J 2
(-3010 3510);
DISPLAY 0.617021 (-3010 3510);
PAINT ORANGE (-3010 3510);
FORCEPROP 2 LASTPIN (-3000 3550) $PN 219
J 2
(-3010 3560);
DISPLAY 0.617021 (-3010 3560);
PAINT ORANGE (-3010 3560);
FORCEPROP 2 LASTPIN (-3000 3600) $PN 218
J 2
(-3010 3610);
DISPLAY 0.617021 (-3010 3610);
PAINT ORANGE (-3010 3610);
FORCEPROP 2 LASTPIN (-3000 3000) $PN 60
J 2
(-3010 3010);
DISPLAY 0.617021 (-3010 3010);
PAINT ORANGE (-3010 3010);
FORCEPROP 2 LASTPIN (-3000 3050) $PN 203
J 2
(-3010 3060);
DISPLAY 0.617021 (-3010 3060);
PAINT ORANGE (-3010 3060);
FORCEPROP 2 LASTPIN (-2000 1650) $PN 5
J 0
(-1990 1660);
DISPLAY 0.617021 (-1990 1660);
PAINT ORANGE (-1990 1660);
FORCEPROP 2 LASTPIN (-2000 1700) $PN 150
J 0
(-1990 1710);
DISPLAY 0.617021 (-1990 1710);
PAINT ORANGE (-1990 1710);
FORCEPROP 2 LASTPIN (-2000 1750) $PN 12
J 0
(-1990 1760);
DISPLAY 0.617021 (-1990 1760);
PAINT ORANGE (-1990 1760);
FORCEPROP 2 LASTPIN (-2000 1800) $PN 157
J 0
(-1990 1810);
DISPLAY 0.617021 (-1990 1810);
PAINT ORANGE (-1990 1810);
FORCEPROP 2 LASTPIN (-2000 1850) $PN 3
J 0
(-1990 1860);
DISPLAY 0.617021 (-1990 1860);
PAINT ORANGE (-1990 1860);
FORCEPROP 2 LASTPIN (-2000 1900) $PN 148
J 0
(-1990 1910);
DISPLAY 0.617021 (-1990 1910);
PAINT ORANGE (-1990 1910);
FORCEPROP 2 LASTPIN (-2000 1950) $PN 10
J 0
(-1990 1960);
DISPLAY 0.617021 (-1990 1960);
PAINT ORANGE (-1990 1960);
FORCEPROP 2 LASTPIN (-2000 2000) $PN 155
J 0
(-1990 2010);
DISPLAY 0.617021 (-1990 2010);
PAINT ORANGE (-1990 2010);
FORCEPROP 2 LASTPIN (-2000 2050) $PN 16
J 0
(-1990 2060);
DISPLAY 0.617021 (-1990 2060);
PAINT ORANGE (-1990 2060);
FORCEPROP 2 LASTPIN (-2000 2100) $PN 161
J 0
(-1990 2110);
DISPLAY 0.617021 (-1990 2110);
PAINT ORANGE (-1990 2110);
FORCEPROP 2 LASTPIN (-2000 2150) $PN 23
J 0
(-1990 2160);
DISPLAY 0.617021 (-1990 2160);
PAINT ORANGE (-1990 2160);
FORCEPROP 2 LASTPIN (-2000 2200) $PN 168
J 0
(-1990 2210);
DISPLAY 0.617021 (-1990 2210);
PAINT ORANGE (-1990 2210);
FORCEPROP 2 LASTPIN (-2000 2250) $PN 14
J 0
(-1990 2260);
DISPLAY 0.617021 (-1990 2260);
PAINT ORANGE (-1990 2260);
FORCEPROP 2 LASTPIN (-2000 2300) $PN 159
J 0
(-1990 2310);
DISPLAY 0.617021 (-1990 2310);
PAINT ORANGE (-1990 2310);
FORCEPROP 2 LASTPIN (-2000 2350) $PN 21
J 0
(-1990 2360);
DISPLAY 0.617021 (-1990 2360);
PAINT ORANGE (-1990 2360);
FORCEPROP 2 LASTPIN (-2000 2400) $PN 166
J 0
(-1990 2410);
DISPLAY 0.617021 (-1990 2410);
PAINT ORANGE (-1990 2410);
FORCEPROP 2 LASTPIN (-2000 2450) $PN 27
J 0
(-1990 2460);
DISPLAY 0.617021 (-1990 2460);
PAINT ORANGE (-1990 2460);
FORCEPROP 2 LASTPIN (-2000 2500) $PN 172
J 0
(-1990 2510);
DISPLAY 0.617021 (-1990 2510);
PAINT ORANGE (-1990 2510);
FORCEPROP 2 LASTPIN (-2000 2550) $PN 34
J 0
(-1990 2560);
DISPLAY 0.617021 (-1990 2560);
PAINT ORANGE (-1990 2560);
FORCEPROP 2 LASTPIN (-2000 2600) $PN 179
J 0
(-1990 2610);
DISPLAY 0.617021 (-1990 2610);
PAINT ORANGE (-1990 2610);
FORCEPROP 2 LASTPIN (-2000 2650) $PN 25
J 0
(-1990 2660);
DISPLAY 0.617021 (-1990 2660);
PAINT ORANGE (-1990 2660);
FORCEPROP 2 LASTPIN (-2000 2700) $PN 170
J 0
(-1990 2710);
DISPLAY 0.617021 (-1990 2710);
PAINT ORANGE (-1990 2710);
FORCEPROP 2 LASTPIN (-2000 2750) $PN 32
J 0
(-1990 2760);
DISPLAY 0.617021 (-1990 2760);
PAINT ORANGE (-1990 2760);
FORCEPROP 2 LASTPIN (-2000 2800) $PN 177
J 0
(-1990 2810);
DISPLAY 0.617021 (-1990 2810);
PAINT ORANGE (-1990 2810);
FORCEPROP 2 LASTPIN (-2000 2850) $PN 38
J 0
(-1990 2860);
DISPLAY 0.617021 (-1990 2860);
PAINT ORANGE (-1990 2860);
FORCEPROP 2 LASTPIN (-2000 2900) $PN 183
J 0
(-1990 2910);
DISPLAY 0.617021 (-1990 2910);
PAINT ORANGE (-1990 2910);
FORCEPROP 2 LASTPIN (-2000 2950) $PN 45
J 0
(-1990 2960);
DISPLAY 0.617021 (-1990 2960);
PAINT ORANGE (-1990 2960);
FORCEPROP 2 LASTPIN (-2000 3000) $PN 190
J 0
(-1990 3010);
DISPLAY 0.617021 (-1990 3010);
PAINT ORANGE (-1990 3010);
FORCEPROP 2 LASTPIN (-2000 3050) $PN 36
J 0
(-1990 3060);
DISPLAY 0.617021 (-1990 3060);
PAINT ORANGE (-1990 3060);
FORCEPROP 2 LASTPIN (-2000 3100) $PN 181
J 0
(-1990 3110);
DISPLAY 0.617021 (-1990 3110);
PAINT ORANGE (-1990 3110);
FORCEPROP 2 LASTPIN (-2000 3150) $PN 43
J 0
(-1990 3160);
DISPLAY 0.617021 (-1990 3160);
PAINT ORANGE (-1990 3160);
FORCEPROP 2 LASTPIN (-2000 3200) $PN 188
J 0
(-1990 3210);
DISPLAY 0.617021 (-1990 3210);
PAINT ORANGE (-1990 3210);
FORCEPROP 2 LASTPIN (-2000 3250) $PN 97
J 0
(-1990 3260);
DISPLAY 0.617021 (-1990 3260);
PAINT ORANGE (-1990 3260);
FORCEPROP 2 LASTPIN (-2000 3300) $PN 242
J 0
(-1990 3310);
DISPLAY 0.617021 (-1990 3310);
PAINT ORANGE (-1990 3310);
FORCEPROP 2 LASTPIN (-2000 3350) $PN 104
J 0
(-1990 3360);
DISPLAY 0.617021 (-1990 3360);
PAINT ORANGE (-1990 3360);
FORCEPROP 2 LASTPIN (-2000 3450) $PN 95
J 0
(-1990 3460);
DISPLAY 0.617021 (-1990 3460);
PAINT ORANGE (-1990 3460);
FORCEPROP 2 LASTPIN (-2000 3500) $PN 240
J 0
(-1990 3510);
DISPLAY 0.617021 (-1990 3510);
PAINT ORANGE (-1990 3510);
FORCEPROP 2 LASTPIN (-2000 3550) $PN 102
J 0
(-1990 3560);
DISPLAY 0.617021 (-1990 3560);
PAINT ORANGE (-1990 3560);
FORCEPROP 2 LASTPIN (-2000 3600) $PN 247
J 0
(-1990 3610);
DISPLAY 0.617021 (-1990 3610);
PAINT ORANGE (-1990 3610);
FORCEPROP 2 LASTPIN (-2000 3650) $PN 108
J 0
(-1990 3660);
DISPLAY 0.617021 (-1990 3660);
PAINT ORANGE (-1990 3660);
FORCEPROP 2 LASTPIN (-2000 3700) $PN 253
J 0
(-1990 3710);
DISPLAY 0.617021 (-1990 3710);
PAINT ORANGE (-1990 3710);
FORCEPROP 2 LASTPIN (-2000 3750) $PN 115
J 0
(-1990 3760);
DISPLAY 0.617021 (-1990 3760);
PAINT ORANGE (-1990 3760);
FORCEPROP 2 LASTPIN (-2000 3800) $PN 260
J 0
(-1990 3810);
DISPLAY 0.617021 (-1990 3810);
PAINT ORANGE (-1990 3810);
FORCEPROP 2 LASTPIN (-2000 3850) $PN 106
J 0
(-1990 3860);
DISPLAY 0.617021 (-1990 3860);
PAINT ORANGE (-1990 3860);
FORCEPROP 2 LASTPIN (-2000 3900) $PN 251
J 0
(-1990 3910);
DISPLAY 0.617021 (-1990 3910);
PAINT ORANGE (-1990 3910);
FORCEPROP 2 LASTPIN (-2000 3950) $PN 113
J 0
(-1990 3960);
DISPLAY 0.617021 (-1990 3960);
PAINT ORANGE (-1990 3960);
FORCEPROP 2 LASTPIN (-2000 4000) $PN 258
J 0
(-1990 4010);
DISPLAY 0.617021 (-1990 4010);
PAINT ORANGE (-1990 4010);
FORCEPROP 2 LASTPIN (-2000 4050) $PN 119
J 0
(-1990 4060);
DISPLAY 0.617021 (-1990 4060);
PAINT ORANGE (-1990 4060);
FORCEPROP 2 LASTPIN (-2000 4100) $PN 264
J 0
(-1990 4110);
DISPLAY 0.617021 (-1990 4110);
PAINT ORANGE (-1990 4110);
FORCEPROP 2 LASTPIN (-2000 4150) $PN 126
J 0
(-1990 4160);
DISPLAY 0.617021 (-1990 4160);
PAINT ORANGE (-1990 4160);
FORCEPROP 2 LASTPIN (-2000 4200) $PN 271
J 0
(-1990 4210);
DISPLAY 0.617021 (-1990 4210);
PAINT ORANGE (-1990 4210);
FORCEPROP 2 LASTPIN (-2000 4250) $PN 117
J 0
(-1990 4260);
DISPLAY 0.617021 (-1990 4260);
PAINT ORANGE (-1990 4260);
FORCEPROP 2 LASTPIN (-2000 4300) $PN 262
J 0
(-1990 4310);
DISPLAY 0.617021 (-1990 4310);
PAINT ORANGE (-1990 4310);
FORCEPROP 2 LASTPIN (-2000 4350) $PN 124
J 0
(-1990 4360);
DISPLAY 0.617021 (-1990 4360);
PAINT ORANGE (-1990 4360);
FORCEPROP 2 LASTPIN (-2000 4500) $PN 275
J 0
(-1990 4510);
DISPLAY 0.617021 (-1990 4510);
PAINT ORANGE (-1990 4510);
FORCEPROP 2 LASTPIN (-2000 4600) $PN 282
J 0
(-1990 4610);
DISPLAY 0.617021 (-1990 4610);
PAINT ORANGE (-1990 4610);
FORCEPROP 2 LASTPIN (-2000 4650) $PN 128
J 0
(-1990 4660);
DISPLAY 0.617021 (-1990 4660);
PAINT ORANGE (-1990 4660);
FORCEPROP 2 LASTPIN (-2000 4800) $PN 280
J 0
(-1990 4810);
DISPLAY 0.617021 (-1990 4810);
PAINT ORANGE (-1990 4810);
FORCEPROP 2 LASTPIN (-3000 2200) $PN 78
J 2
(-3010 2210);
DISPLAY 0.617021 (-3010 2210);
PAINT ORANGE (-3010 2210);
FORCEPROP 2 LASTPIN (-3000 2850) $PN 87
J 2
(-3010 2860);
DISPLAY 0.617021 (-3010 2860);
PAINT ORANGE (-3010 2860);
FORCEPROP 2 LASTPIN (-3000 2900) $PN 91
J 2
(-3010 2910);
DISPLAY 0.617021 (-3010 2910);
PAINT ORANGE (-3010 2910);
FORCEPROP 2 LASTPIN (-3000 2300) $PN 222
J 2
(-3010 2310);
DISPLAY 0.617021 (-3010 2310);
PAINT ORANGE (-3010 2310);
FORCEPROP 2 LASTPIN (-3000 2250) $PN 58
J 2
(-3010 2260);
DISPLAY 0.617021 (-3010 2260);
PAINT ORANGE (-3010 2260);
FORCEPROP 2 LASTPIN (-3000 1450) $PN 205
J 2
(-3010 1460);
DISPLAY 0.617021 (-3010 1460);
PAINT ORANGE (-3010 1460);
FORCEPROP 2 LASTPIN (-3000 1500) $PN 227
J 2
(-3010 1510);
DISPLAY 0.617021 (-3010 1510);
PAINT ORANGE (-3010 1510);
FORCEPROP 2 LASTPIN (-3000 1550) $PN 144
J 2
(-3010 1560);
DISPLAY 0.617021 (-3010 1560);
PAINT ORANGE (-3010 1560);
FORCEPROP 2 LASTPIN (-3000 3150) $PN 84
J 2
(-3010 3160);
DISPLAY 0.617021 (-3010 3160);
PAINT ORANGE (-3010 3160);
FORCEPROP 2 LASTPIN (-3000 3200) $PN 89
J 2
(-3010 3210);
DISPLAY 0.617021 (-3010 3210);
PAINT ORANGE (-3010 3210);
FORCEPROP 2 LASTPIN (-3000 3250) $PN 93
J 2
(-3010 3260);
DISPLAY 0.617021 (-3010 3260);
PAINT ORANGE (-3010 3260);
FORCEPROP 2 LASTPIN (-3000 3300) $PN 237
J 2
(-3010 3310);
DISPLAY 0.617021 (-3010 3310);
PAINT ORANGE (-3010 3310);
FORCEPROP 2 LASTPIN (-3000 1850) $PN 139
J 2
(-3010 1860);
DISPLAY 0.617021 (-3010 1860);
PAINT ORANGE (-3010 1860);
FORCEPROP 2 LASTPIN (-3000 1900) $PN 140
J 2
(-3010 1910);
DISPLAY 0.617021 (-3010 1910);
PAINT ORANGE (-3010 1910);
FORCEPROP 2 LASTPIN (-3000 1950) $PN 238
J 2
(-3010 1960);
DISPLAY 0.617021 (-3010 1960);
PAINT ORANGE (-3010 1960);
FORCEPROP 2 LASTPIN (-3000 1350) $PN 230
J 2
(-3010 1360);
DISPLAY 0.617021 (-3010 1360);
PAINT ORANGE (-3010 1360);
FORCEPROP 2 LASTPIN (-3000 1750) $PN 141
J 2
(-3010 1760);
DISPLAY 0.617021 (-3010 1760);
PAINT ORANGE (-3010 1760);
FORCEPROP 2 LASTPIN (-3000 1800) $PN 285
J 2
(-3010 1810);
DISPLAY 0.617021 (-3010 1810);
PAINT ORANGE (-3010 1810);
FORCEPROP 2 LASTPIN (-3000 2000) $PN 284
J 2
(-3010 2010);
DISPLAY 0.617021 (-3010 2010);
PAINT ORANGE (-3010 2010);
FORCEPROP 2 LASTPIN (-3000 1650) $PN 146
J 2
(-3010 1660);
DISPLAY 0.617021 (-3010 1660);
PAINT ORANGE (-3010 1660);
FORCEPROP 1 LAST PART_NUMBER H44441-003
J 0
(-2950 1150);
DISPLAY 0.617021 (-2950 1150);
PAINT BLUE (-2950 1150);
FORCEPROP 1 LAST LOCATION J9U2
J 0
(-2950 5050);
DISPLAY 0.617021 (-2950 5050);
PAINT AQUA (-2950 5050);
FORCEPROP 2 LAST ROOM DDR4_CH_J
J 0
(-2500 3150);
PAINT ORANGE (-2500 3150);
DISPLAY INVISIBLE (-2500 3150);
FORCEPROP 1 LAST PATH I187
J 0
(-2500 5000);
PAINT GREEN (-2500 5000);
DISPLAY INVISIBLE (-2500 5000);
FORCEPROP 2 LAST CDS_LOCATION J9U2
J 0
(-2950 5050);
DISPLAY 0.617021 (-2950 5050);
PAINT AQUA (-2950 5050);
DISPLAY INVISIBLE (-2950 5050);
FORCEPROP 2 LAST SEC 1
J 0
(-2950 5100);
DISPLAY 0.680851 (-2950 5100);
PAINT MONO (-2950 5100);
DISPLAY INVISIBLE (-2950 5100);
FORCEPROP 2 LAST SEC_TYPE PIP
J 0
(-2950 5100);
DISPLAY 1.021277 (-2950 5100);
PAINT ORANGE (-2950 5100);
DISPLAY INVISIBLE (-2950 5100);
FORCEPROP 2 LAST CDS_LIB mstr_sconn
J 0
(-2500 3150);
PAINT ORANGE (-2500 3150);
DISPLAY INVISIBLE (-2500 3150);
FORCEPROP 2 LAST BOM_COST MEM
J 0
(-2500 3150);
PAINT ORANGE (-2500 3150);
DISPLAY INVISIBLE (-2500 3150);
FORCEPROP 1 LAST PACK_TYPE PIP
J 0
(-2950 5100);
PAINT SKYBLUE (-2950 5100);
DISPLAY INVISIBLE (-2950 5100);
FORCEADD SCONN288_H44441003..3
(1750 2350);
FORCEPROP 0 LAST BOM_SS NOPOP
J 0
(1524 3728);
DISPLAY 1.021277 (1524 3728);
PAINT BROWN (1524 3728);
DISPLAY BOTH (1524 3728);
FORCEPROP 2 LASTPIN (2250 3150) $PN 162
J 0
(2260 3160);
DISPLAY 0.617021 (2260 3160);
PAINT ORANGE (2260 3160);
FORCEPROP 2 LASTPIN (2250 2650) $PN 184
J 0
(2260 2660);
DISPLAY 0.617021 (2260 2660);
PAINT ORANGE (2260 2660);
FORCEPROP 2 LASTPIN (2250 2000) $PN 248
J 0
(2260 2010);
DISPLAY 0.617021 (2260 2010);
PAINT ORANGE (2260 2010);
FORCEPROP 2 LASTPIN (2250 1950) $PN 250
J 0
(2260 1960);
DISPLAY 0.617021 (2260 1960);
PAINT ORANGE (2260 1960);
FORCEPROP 2 LASTPIN (2250 1900) $PN 252
J 0
(2260 1910);
DISPLAY 0.617021 (2260 1910);
PAINT ORANGE (2260 1910);
FORCEPROP 2 LASTPIN (2250 1200) $PN 283
J 0
(2260 1210);
DISPLAY 0.617021 (2260 1210);
PAINT ORANGE (2260 1210);
FORCEPROP 2 LASTPIN (2250 1250) $PN 281
J 0
(2260 1260);
DISPLAY 0.617021 (2260 1260);
PAINT ORANGE (2260 1260);
FORCEPROP 2 LASTPIN (2250 1300) $PN 279
J 0
(2260 1310);
DISPLAY 0.617021 (2260 1310);
PAINT ORANGE (2260 1310);
FORCEPROP 2 LASTPIN (2250 1350) $PN 276
J 0
(2260 1360);
DISPLAY 0.617021 (2260 1360);
PAINT ORANGE (2260 1360);
FORCEPROP 2 LASTPIN (2250 1400) $PN 274
J 0
(2260 1410);
DISPLAY 0.617021 (2260 1410);
PAINT ORANGE (2260 1410);
FORCEPROP 2 LASTPIN (2250 1450) $PN 272
J 0
(2260 1460);
DISPLAY 0.617021 (2260 1460);
PAINT ORANGE (2260 1460);
FORCEPROP 2 LASTPIN (2250 1500) $PN 270
J 0
(2260 1510);
DISPLAY 0.617021 (2260 1510);
PAINT ORANGE (2260 1510);
FORCEPROP 2 LASTPIN (2250 1550) $PN 268
J 0
(2260 1560);
DISPLAY 0.617021 (2260 1560);
PAINT ORANGE (2260 1560);
FORCEPROP 2 LASTPIN (2250 1600) $PN 265
J 0
(2260 1610);
DISPLAY 0.617021 (2260 1610);
PAINT ORANGE (2260 1610);
FORCEPROP 2 LASTPIN (2250 1650) $PN 263
J 0
(2260 1660);
DISPLAY 0.617021 (2260 1660);
PAINT ORANGE (2260 1660);
FORCEPROP 2 LASTPIN (2250 1700) $PN 261
J 0
(2260 1710);
DISPLAY 0.617021 (2260 1710);
PAINT ORANGE (2260 1710);
FORCEPROP 2 LASTPIN (2250 1750) $PN 259
J 0
(2260 1760);
DISPLAY 0.617021 (2260 1760);
PAINT ORANGE (2260 1760);
FORCEPROP 2 LASTPIN (2250 1800) $PN 257
J 0
(2260 1810);
DISPLAY 0.617021 (2260 1810);
PAINT ORANGE (2260 1810);
FORCEPROP 2 LASTPIN (2250 1850) $PN 254
J 0
(2260 1860);
DISPLAY 0.617021 (2260 1860);
PAINT ORANGE (2260 1860);
FORCEPROP 2 LASTPIN (2250 2050) $PN 246
J 0
(2260 2060);
DISPLAY 0.617021 (2260 2060);
PAINT ORANGE (2260 2060);
FORCEPROP 2 LASTPIN (2250 2100) $PN 243
J 0
(2260 2110);
DISPLAY 0.617021 (2260 2110);
PAINT ORANGE (2260 2110);
FORCEPROP 2 LASTPIN (2250 2150) $PN 241
J 0
(2260 2160);
DISPLAY 0.617021 (2260 2160);
PAINT ORANGE (2260 2160);
FORCEPROP 2 LASTPIN (2250 2200) $PN 239
J 0
(2260 2210);
DISPLAY 0.617021 (2260 2210);
PAINT ORANGE (2260 2210);
FORCEPROP 2 LASTPIN (2250 2250) $PN 202
J 0
(2260 2260);
DISPLAY 0.617021 (2260 2260);
PAINT ORANGE (2260 2260);
FORCEPROP 2 LASTPIN (2250 2300) $PN 200
J 0
(2260 2310);
DISPLAY 0.617021 (2260 2310);
PAINT ORANGE (2260 2310);
FORCEPROP 2 LASTPIN (2250 2350) $PN 198
J 0
(2260 2360);
DISPLAY 0.617021 (2260 2360);
PAINT ORANGE (2260 2360);
FORCEPROP 2 LASTPIN (2250 2400) $PN 195
J 0
(2260 2410);
DISPLAY 0.617021 (2260 2410);
PAINT ORANGE (2260 2410);
FORCEPROP 2 LASTPIN (2250 2450) $PN 193
J 0
(2260 2460);
DISPLAY 0.617021 (2260 2460);
PAINT ORANGE (2260 2460);
FORCEPROP 2 LASTPIN (2250 2500) $PN 191
J 0
(2260 2510);
DISPLAY 0.617021 (2260 2510);
PAINT ORANGE (2260 2510);
FORCEPROP 2 LASTPIN (2250 2550) $PN 189
J 0
(2260 2560);
DISPLAY 0.617021 (2260 2560);
PAINT ORANGE (2260 2560);
FORCEPROP 2 LASTPIN (2250 2600) $PN 187
J 0
(2260 2610);
DISPLAY 0.617021 (2260 2610);
PAINT ORANGE (2260 2610);
FORCEPROP 2 LASTPIN (2250 2700) $PN 182
J 0
(2260 2710);
DISPLAY 0.617021 (2260 2710);
PAINT ORANGE (2260 2710);
FORCEPROP 2 LASTPIN (2250 2750) $PN 180
J 0
(2260 2760);
DISPLAY 0.617021 (2260 2760);
PAINT ORANGE (2260 2760);
FORCEPROP 2 LASTPIN (2250 2800) $PN 178
J 0
(2260 2810);
DISPLAY 0.617021 (2260 2810);
PAINT ORANGE (2260 2810);
FORCEPROP 2 LASTPIN (2250 2850) $PN 176
J 0
(2260 2860);
DISPLAY 0.617021 (2260 2860);
PAINT ORANGE (2260 2860);
FORCEPROP 2 LASTPIN (2250 2900) $PN 173
J 0
(2260 2910);
DISPLAY 0.617021 (2260 2910);
PAINT ORANGE (2260 2910);
FORCEPROP 2 LASTPIN (2250 2950) $PN 171
J 0
(2260 2960);
DISPLAY 0.617021 (2260 2960);
PAINT ORANGE (2260 2960);
FORCEPROP 2 LASTPIN (2250 3000) $PN 169
J 0
(2260 3010);
DISPLAY 0.617021 (2260 3010);
PAINT ORANGE (2260 3010);
FORCEPROP 2 LASTPIN (2250 3050) $PN 167
J 0
(2260 3060);
DISPLAY 0.617021 (2260 3060);
PAINT ORANGE (2260 3060);
FORCEPROP 2 LASTPIN (2250 3100) $PN 165
J 0
(2260 3110);
DISPLAY 0.617021 (2260 3110);
PAINT ORANGE (2260 3110);
FORCEPROP 2 LASTPIN (2250 3200) $PN 160
J 0
(2260 3210);
DISPLAY 0.617021 (2260 3210);
PAINT ORANGE (2260 3210);
FORCEPROP 2 LASTPIN (2250 3250) $PN 158
J 0
(2260 3260);
DISPLAY 0.617021 (2260 3260);
PAINT ORANGE (2260 3260);
FORCEPROP 2 LASTPIN (2250 3300) $PN 156
J 0
(2260 3310);
DISPLAY 0.617021 (2260 3310);
PAINT ORANGE (2260 3310);
FORCEPROP 2 LASTPIN (2250 3350) $PN 154
J 0
(2260 3360);
DISPLAY 0.617021 (2260 3360);
PAINT ORANGE (2260 3360);
FORCEPROP 2 LASTPIN (2250 3400) $PN 151
J 0
(2260 3410);
DISPLAY 0.617021 (2260 3410);
PAINT ORANGE (2260 3410);
FORCEPROP 2 LASTPIN (2250 3450) $PN 149
J 0
(2260 3460);
DISPLAY 0.617021 (2260 3460);
PAINT ORANGE (2260 3460);
FORCEPROP 2 LASTPIN (2250 3500) $PN 147
J 0
(2260 3510);
DISPLAY 0.617021 (2260 3510);
PAINT ORANGE (2260 3510);
FORCEPROP 2 LASTPIN (1250 1200) $PN 138
J 2
(1240 1210);
DISPLAY 0.617021 (1240 1210);
PAINT ORANGE (1240 1210);
FORCEPROP 2 LASTPIN (1250 1250) $PN 136
J 2
(1240 1260);
DISPLAY 0.617021 (1240 1260);
PAINT ORANGE (1240 1260);
FORCEPROP 2 LASTPIN (1250 1300) $PN 134
J 2
(1240 1310);
DISPLAY 0.617021 (1240 1310);
PAINT ORANGE (1240 1310);
FORCEPROP 2 LASTPIN (1250 1350) $PN 131
J 2
(1240 1360);
DISPLAY 0.617021 (1240 1360);
PAINT ORANGE (1240 1360);
FORCEPROP 2 LASTPIN (1250 1400) $PN 129
J 2
(1240 1410);
DISPLAY 0.617021 (1240 1410);
PAINT ORANGE (1240 1410);
FORCEPROP 2 LASTPIN (1250 1450) $PN 127
J 2
(1240 1460);
DISPLAY 0.617021 (1240 1460);
PAINT ORANGE (1240 1460);
FORCEPROP 2 LASTPIN (1250 1500) $PN 125
J 2
(1240 1510);
DISPLAY 0.617021 (1240 1510);
PAINT ORANGE (1240 1510);
FORCEPROP 2 LASTPIN (1250 1550) $PN 123
J 2
(1240 1560);
DISPLAY 0.617021 (1240 1560);
PAINT ORANGE (1240 1560);
FORCEPROP 2 LASTPIN (1250 1600) $PN 120
J 2
(1240 1610);
DISPLAY 0.617021 (1240 1610);
PAINT ORANGE (1240 1610);
FORCEPROP 2 LASTPIN (1250 1650) $PN 118
J 2
(1240 1660);
DISPLAY 0.617021 (1240 1660);
PAINT ORANGE (1240 1660);
FORCEPROP 2 LASTPIN (1250 1700) $PN 116
J 2
(1240 1710);
DISPLAY 0.617021 (1240 1710);
PAINT ORANGE (1240 1710);
FORCEPROP 2 LASTPIN (1250 1750) $PN 114
J 2
(1240 1760);
DISPLAY 0.617021 (1240 1760);
PAINT ORANGE (1240 1760);
FORCEPROP 2 LASTPIN (1250 1800) $PN 112
J 2
(1240 1810);
DISPLAY 0.617021 (1240 1810);
PAINT ORANGE (1240 1810);
FORCEPROP 2 LASTPIN (1250 1850) $PN 109
J 2
(1240 1860);
DISPLAY 0.617021 (1240 1860);
PAINT ORANGE (1240 1860);
FORCEPROP 2 LASTPIN (1250 1900) $PN 107
J 2
(1240 1910);
DISPLAY 0.617021 (1240 1910);
PAINT ORANGE (1240 1910);
FORCEPROP 2 LASTPIN (1250 1950) $PN 105
J 2
(1240 1960);
DISPLAY 0.617021 (1240 1960);
PAINT ORANGE (1240 1960);
FORCEPROP 2 LASTPIN (1250 2000) $PN 103
J 2
(1240 2010);
DISPLAY 0.617021 (1240 2010);
PAINT ORANGE (1240 2010);
FORCEPROP 2 LASTPIN (1250 2050) $PN 101
J 2
(1240 2060);
DISPLAY 0.617021 (1240 2060);
PAINT ORANGE (1240 2060);
FORCEPROP 2 LASTPIN (1250 2100) $PN 98
J 2
(1240 2110);
DISPLAY 0.617021 (1240 2110);
PAINT ORANGE (1240 2110);
FORCEPROP 2 LASTPIN (1250 2150) $PN 96
J 2
(1240 2160);
DISPLAY 0.617021 (1240 2160);
PAINT ORANGE (1240 2160);
FORCEPROP 2 LASTPIN (1250 2200) $PN 94
J 2
(1240 2210);
DISPLAY 0.617021 (1240 2210);
PAINT ORANGE (1240 2210);
FORCEPROP 2 LASTPIN (1250 2250) $PN 57
J 2
(1240 2260);
DISPLAY 0.617021 (1240 2260);
PAINT ORANGE (1240 2260);
FORCEPROP 2 LASTPIN (1250 2300) $PN 55
J 2
(1240 2310);
DISPLAY 0.617021 (1240 2310);
PAINT ORANGE (1240 2310);
FORCEPROP 2 LASTPIN (1250 2350) $PN 53
J 2
(1240 2360);
DISPLAY 0.617021 (1240 2360);
PAINT ORANGE (1240 2360);
FORCEPROP 2 LASTPIN (1250 2400) $PN 50
J 2
(1240 2410);
DISPLAY 0.617021 (1240 2410);
PAINT ORANGE (1240 2410);
FORCEPROP 2 LASTPIN (1250 2450) $PN 48
J 2
(1240 2460);
DISPLAY 0.617021 (1240 2460);
PAINT ORANGE (1240 2460);
FORCEPROP 2 LASTPIN (1250 2500) $PN 46
J 2
(1240 2510);
DISPLAY 0.617021 (1240 2510);
PAINT ORANGE (1240 2510);
FORCEPROP 2 LASTPIN (1250 2550) $PN 44
J 2
(1240 2560);
DISPLAY 0.617021 (1240 2560);
PAINT ORANGE (1240 2560);
FORCEPROP 2 LASTPIN (1250 2600) $PN 42
J 2
(1240 2610);
DISPLAY 0.617021 (1240 2610);
PAINT ORANGE (1240 2610);
FORCEPROP 2 LASTPIN (1250 2650) $PN 39
J 2
(1240 2660);
DISPLAY 0.617021 (1240 2660);
PAINT ORANGE (1240 2660);
FORCEPROP 2 LASTPIN (1250 2700) $PN 37
J 2
(1240 2710);
DISPLAY 0.617021 (1240 2710);
PAINT ORANGE (1240 2710);
FORCEPROP 2 LASTPIN (1250 2750) $PN 35
J 2
(1240 2760);
DISPLAY 0.617021 (1240 2760);
PAINT ORANGE (1240 2760);
FORCEPROP 2 LASTPIN (1250 2800) $PN 33
J 2
(1240 2810);
DISPLAY 0.617021 (1240 2810);
PAINT ORANGE (1240 2810);
FORCEPROP 2 LASTPIN (1250 2850) $PN 31
J 2
(1240 2860);
DISPLAY 0.617021 (1240 2860);
PAINT ORANGE (1240 2860);
FORCEPROP 2 LASTPIN (1250 2900) $PN 28
J 2
(1240 2910);
DISPLAY 0.617021 (1240 2910);
PAINT ORANGE (1240 2910);
FORCEPROP 2 LASTPIN (1250 2950) $PN 26
J 2
(1240 2960);
DISPLAY 0.617021 (1240 2960);
PAINT ORANGE (1240 2960);
FORCEPROP 2 LASTPIN (1250 3000) $PN 24
J 2
(1240 3010);
DISPLAY 0.617021 (1240 3010);
PAINT ORANGE (1240 3010);
FORCEPROP 2 LASTPIN (1250 3050) $PN 22
J 2
(1240 3060);
DISPLAY 0.617021 (1240 3060);
PAINT ORANGE (1240 3060);
FORCEPROP 2 LASTPIN (1250 3100) $PN 20
J 2
(1240 3110);
DISPLAY 0.617021 (1240 3110);
PAINT ORANGE (1240 3110);
FORCEPROP 2 LASTPIN (1250 3150) $PN 17
J 2
(1240 3160);
DISPLAY 0.617021 (1240 3160);
PAINT ORANGE (1240 3160);
FORCEPROP 2 LASTPIN (1250 3200) $PN 15
J 2
(1240 3210);
DISPLAY 0.617021 (1240 3210);
PAINT ORANGE (1240 3210);
FORCEPROP 2 LASTPIN (1250 3250) $PN 13
J 2
(1240 3260);
DISPLAY 0.617021 (1240 3260);
PAINT ORANGE (1240 3260);
FORCEPROP 2 LASTPIN (1250 3300) $PN 11
J 2
(1240 3310);
DISPLAY 0.617021 (1240 3310);
PAINT ORANGE (1240 3310);
FORCEPROP 2 LASTPIN (1250 3350) $PN 9
J 2
(1240 3360);
DISPLAY 0.617021 (1240 3360);
PAINT ORANGE (1240 3360);
FORCEPROP 2 LASTPIN (1250 3400) $PN 6
J 2
(1240 3410);
DISPLAY 0.617021 (1240 3410);
PAINT ORANGE (1240 3410);
FORCEPROP 2 LASTPIN (1250 3450) $PN 4
J 2
(1240 3460);
DISPLAY 0.617021 (1240 3460);
PAINT ORANGE (1240 3460);
FORCEPROP 2 LASTPIN (1250 3500) $PN 2
J 2
(1240 3510);
DISPLAY 0.617021 (1240 3510);
PAINT ORANGE (1240 3510);
FORCEPROP 1 LAST MATERIAL SCONN
J 0
(1300 3700);
DISPLAY 0.617021 (1300 3700);
PAINT SKYBLUE (1300 3700);
FORCEPROP 1 LAST PART_NUMBER H44441-003
J 0
(1300 1000);
DISPLAY 0.617021 (1300 1000);
PAINT BLUE (1300 1000);
FORCEPROP 1 LAST LOCATION J9U2
J 0
(1300 3750);
DISPLAY 0.617021 (1300 3750);
PAINT AQUA (1300 3750);
FORCEPROP 2 LAST ROOM DDR4_CH_J
J 0
(1750 2350);
PAINT ORANGE (1750 2350);
DISPLAY INVISIBLE (1750 2350);
FORCEPROP 1 LAST PATH I188
J 0
(1750 3700);
PAINT GREEN (1750 3700);
DISPLAY INVISIBLE (1750 3700);
FORCEPROP 2 LAST CDS_LOCATION J9U2
J 0
(1300 3750);
DISPLAY 0.617021 (1300 3750);
PAINT AQUA (1300 3750);
DISPLAY INVISIBLE (1300 3750);
FORCEPROP 2 LAST SEC 3
J 0
(1300 3800);
DISPLAY 0.680851 (1300 3800);
PAINT MONO (1300 3800);
DISPLAY INVISIBLE (1300 3800);
FORCEPROP 2 LAST SEC_TYPE PIP
J 0
(1300 3800);
DISPLAY 1.021277 (1300 3800);
PAINT ORANGE (1300 3800);
DISPLAY INVISIBLE (1300 3800);
FORCEPROP 2 LAST CDS_LIB mstr_sconn
J 0
(1750 2350);
PAINT ORANGE (1750 2350);
DISPLAY INVISIBLE (1750 2350);
FORCEPROP 2 LAST BOM_COST MEM
J 0
(1750 2350);
PAINT ORANGE (1750 2350);
DISPLAY INVISIBLE (1750 2350);
FORCEPROP 1 LAST PACK_TYPE PIP
J 0
(1300 3800);
PAINT SKYBLUE (1300 3800);
DISPLAY INVISIBLE (1300 3800);
FORCEADD GND..1
(-5200 1800);
FORCEPROP 3 LASTPIN (-5200 1850) SIG_NAME GND\g
J 0
(-5190 1860);
DISPLAY 0.659574 (-5190 1860);
PAINT MONO (-5190 1860);
DISPLAY INVISIBLE (-5190 1860);
FORCEPROP 1 LAST HDL_POWER GND
J 0
(-5200 1950);
DISPLAY 1.404255 (-5200 1950);
PAINT GREEN (-5200 1950);
DISPLAY INVISIBLE (-5200 1950);
FORCEPROP 2 LAST ROOM DDR4_CH_J
J 0
(-5200 1805);
PAINT ORANGE (-5200 1805);
DISPLAY INVISIBLE (-5200 1805);
FORCEPROP 1 LAST PATH I189
J 0
(-5125 1800);
DISPLAY 0.872340 (-5125 1800);
PAINT AQUA (-5125 1800);
DISPLAY INVISIBLE (-5125 1800);
FORCEPROP 1 LAST BODY_TYPE PLUMBING
J 0
(-5245 1757);
DISPLAY 0.340426 (-5245 1757);
PAINT GREEN (-5245 1757);
DISPLAY INVISIBLE (-5245 1757);
FORCEPROP 2 LAST CDS_LIB mstr_symbols
J 0
(-5200 1800);
PAINT ORANGE (-5200 1800);
DISPLAY INVISIBLE (-5200 1800);
FORCEPROP 1 LAST SIZE 1B
J 0
(-5125 1750);
DISPLAY 1.787234 (-5125 1750);
PAINT GREEN (-5125 1750);
DISPLAY INVISIBLE (-5125 1750);
FORCEPROP 2 LAST BOM_COST MEM
J 0
(-5200 1805);
PAINT ORANGE (-5200 1805);
DISPLAY INVISIBLE (-5200 1805);
FORCEPROP 1 LAST VOLTAGE 0
J 0
(-5200 1800);
PAINT SKYBLUE (-5200 1800);
DISPLAY INVISIBLE (-5200 1800);
FORCEADD TAP..6
R 2
(850 4400);
FORCEPROP 3 LASTPIN (800 4400) SIG_NAME M_J_DQS_DN<10>
J 0
(810 4410);
DISPLAY 0.659574 (810 4410);
PAINT MONO (810 4410);
DISPLAY INVISIBLE (810 4410);
FORCEPROP 1 LASTPIN (800 4400) BN 10
J 2
(850 4410);
DISPLAY 0.617021 (850 4410);
PAINT PINK (850 4410);
FORCEPROP 1 LAST PATH I19
J 2
(850 4400);
DISPLAY 0.936170 (850 4400);
PAINT GREEN (850 4400);
DISPLAY INVISIBLE (850 4400);
FORCEPROP 1 LAST HDL_TAP TRUE
J 2
(525 4275);
DISPLAY 1.234043 (525 4275);
PAINT GREEN (525 4275);
DISPLAY INVISIBLE (525 4275);
FORCEPROP 1 LAST BODY_TYPE PLUMBING
J 2
(850 4350);
DISPLAY 1.234043 (850 4350);
PAINT GREEN (850 4350);
DISPLAY INVISIBLE (850 4350);
FORCEPROP 2 LAST CDS_LIB mstr_standard
J 0
(850 4400);
DISPLAY 0.787234 (850 4400);
PAINT MONO (850 4400);
DISPLAY INVISIBLE (850 4400);
FORCEADD P12V_NVDIMM_GHJ..1
(350 3025);
FORCEPROP 3 LASTPIN (350 2975) SIG_NAME P12V_NVDIMM_GHJ\g
J 0
(360 2985);
DISPLAY 0.659574 (360 2985);
PAINT MONO (360 2985);
DISPLAY INVISIBLE (360 2985);
FORCEPROP 1 LAST HDL_POWER P12V_NVDIMM_GHJ
J 1
(350 3075);
DISPLAY 0.872340 (350 3075);
PAINT GREEN (350 3075);
DISPLAY INVISIBLE (350 3075);
FORCEPROP 1 LAST PATH I190
J 0
(400 3050);
DISPLAY 0.872340 (400 3050);
PAINT AQUA (400 3050);
DISPLAY INVISIBLE (400 3050);
FORCEPROP 1 LAST BODY_TYPE PLUMBING
J 0
(305 2982);
DISPLAY 0.340426 (305 2982);
PAINT GREEN (305 2982);
DISPLAY INVISIBLE (305 2982);
FORCEPROP 2 LAST CDS_LIB mstr_symbols
J 0
(350 3025);
PAINT ORANGE (350 3025);
DISPLAY INVISIBLE (350 3025);
FORCEPROP 1 LAST VOLTAGE 12.0
J 0
(305 2982);
DISPLAY 0.340426 (305 2982);
PAINT SKYBLUE (305 2982);
DISPLAY INVISIBLE (305 2982);
FORCEADD OFFPAGE..3
(1550 5200);
FORCEPROP 2 LAST $XR1 81 
J 0
(1854 5200);
DISPLAY 0.638298 (1854 5200);
PAINT MONO (1854 5200);
FORCEPROP 2 LAST $XR0 59 
J 0
(1764 5200);
DISPLAY 0.638298 (1764 5200);
PAINT MONO (1764 5200);
FORCEPROP 2 LAST PATH I2
J 0
(1750 5275);
DISPLAY 0.787234 (1750 5275);
PAINT MONO (1750 5275);
DISPLAY INVISIBLE (1750 5275);
FORCEPROP 1 LAST COMMENT_BODY TRUE
J 0
(1500 5100);
DISPLAY 0.936170 (1500 5100);
PAINT GREEN (1500 5100);
DISPLAY INVISIBLE (1500 5100);
FORCEPROP 1 LAST OFFPAGE TRUE
J 0
(1875 5075);
DISPLAY 0.936170 (1875 5075);
PAINT GREEN (1875 5075);
DISPLAY INVISIBLE (1875 5075);
FORCEPROP 2 LAST CDS_LIB mstr_standard
J 0
(1550 5200);
DISPLAY 0.787234 (1550 5200);
PAINT MONO (1550 5200);
DISPLAY INVISIBLE (1550 5200);
FORCEADD TAP..6
R 2
(850 4200);
FORCEPROP 3 LASTPIN (800 4200) SIG_NAME M_J_DQS_DN<8>
J 0
(810 4210);
DISPLAY 0.659574 (810 4210);
PAINT MONO (810 4210);
DISPLAY INVISIBLE (810 4210);
FORCEPROP 1 LASTPIN (800 4200) BN 8
J 2
(850 4210);
DISPLAY 0.617021 (850 4210);
PAINT PINK (850 4210);
FORCEPROP 1 LAST PATH I20
J 2
(850 4200);
DISPLAY 0.936170 (850 4200);
PAINT GREEN (850 4200);
DISPLAY INVISIBLE (850 4200);
FORCEPROP 1 LAST HDL_TAP TRUE
J 2
(525 4075);
DISPLAY 1.234043 (525 4075);
PAINT GREEN (525 4075);
DISPLAY INVISIBLE (525 4075);
FORCEPROP 1 LAST BODY_TYPE PLUMBING
J 2
(850 4150);
DISPLAY 1.234043 (850 4150);
PAINT GREEN (850 4150);
DISPLAY INVISIBLE (850 4150);
FORCEPROP 2 LAST CDS_LIB mstr_standard
J 0
(850 4200);
DISPLAY 0.787234 (850 4200);
PAINT MONO (850 4200);
DISPLAY INVISIBLE (850 4200);
FORCEADD TAP..6
R 2
(850 4300);
FORCEPROP 3 LASTPIN (800 4300) SIG_NAME M_J_DQS_DN<9>
J 0
(810 4310);
DISPLAY 0.659574 (810 4310);
PAINT MONO (810 4310);
DISPLAY INVISIBLE (810 4310);
FORCEPROP 1 LASTPIN (800 4300) BN 9
J 2
(850 4310);
DISPLAY 0.617021 (850 4310);
PAINT PINK (850 4310);
FORCEPROP 1 LAST PATH I21
J 2
(850 4300);
DISPLAY 0.936170 (850 4300);
PAINT GREEN (850 4300);
DISPLAY INVISIBLE (850 4300);
FORCEPROP 1 LAST HDL_TAP TRUE
J 2
(525 4175);
DISPLAY 1.234043 (525 4175);
PAINT GREEN (525 4175);
DISPLAY INVISIBLE (525 4175);
FORCEPROP 1 LAST BODY_TYPE PLUMBING
J 2
(850 4250);
DISPLAY 1.234043 (850 4250);
PAINT GREEN (850 4250);
DISPLAY INVISIBLE (850 4250);
FORCEPROP 2 LAST CDS_LIB mstr_standard
J 0
(850 4300);
DISPLAY 0.787234 (850 4300);
PAINT MONO (850 4300);
DISPLAY INVISIBLE (850 4300);
FORCEADD TAP..6
R 2
(650 4550);
FORCEPROP 3 LASTPIN (600 4550) SIG_NAME M_J_DQS_DP<11>
J 0
(610 4560);
DISPLAY 0.659574 (610 4560);
PAINT MONO (610 4560);
DISPLAY INVISIBLE (610 4560);
FORCEPROP 1 LASTPIN (600 4550) BN 11
J 2
(650 4560);
DISPLAY 0.617021 (650 4560);
PAINT PINK (650 4560);
FORCEPROP 1 LAST PATH I22
J 2
(650 4550);
DISPLAY 0.936170 (650 4550);
PAINT GREEN (650 4550);
DISPLAY INVISIBLE (650 4550);
FORCEPROP 1 LAST HDL_TAP TRUE
J 2
(325 4425);
DISPLAY 1.234043 (325 4425);
PAINT GREEN (325 4425);
DISPLAY INVISIBLE (325 4425);
FORCEPROP 1 LAST BODY_TYPE PLUMBING
J 2
(650 4500);
DISPLAY 1.234043 (650 4500);
PAINT GREEN (650 4500);
DISPLAY INVISIBLE (650 4500);
FORCEPROP 2 LAST CDS_LIB mstr_standard
J 0
(650 4550);
DISPLAY 0.787234 (650 4550);
PAINT MONO (650 4550);
DISPLAY INVISIBLE (650 4550);
FORCEADD TAP..6
R 2
(650 4450);
FORCEPROP 3 LASTPIN (600 4450) SIG_NAME M_J_DQS_DP<10>
J 0
(610 4460);
DISPLAY 0.659574 (610 4460);
PAINT MONO (610 4460);
DISPLAY INVISIBLE (610 4460);
FORCEPROP 1 LASTPIN (600 4450) BN 10
J 2
(650 4460);
DISPLAY 0.617021 (650 4460);
PAINT PINK (650 4460);
FORCEPROP 1 LAST PATH I23
J 2
(650 4450);
DISPLAY 0.936170 (650 4450);
PAINT GREEN (650 4450);
DISPLAY INVISIBLE (650 4450);
FORCEPROP 1 LAST HDL_TAP TRUE
J 2
(325 4325);
DISPLAY 1.234043 (325 4325);
PAINT GREEN (325 4325);
DISPLAY INVISIBLE (325 4325);
FORCEPROP 1 LAST BODY_TYPE PLUMBING
J 2
(650 4400);
DISPLAY 1.234043 (650 4400);
PAINT GREEN (650 4400);
DISPLAY INVISIBLE (650 4400);
FORCEPROP 2 LAST CDS_LIB mstr_standard
J 0
(650 4450);
DISPLAY 0.787234 (650 4450);
PAINT MONO (650 4450);
DISPLAY INVISIBLE (650 4450);
FORCEADD TAP..6
R 2
(650 4350);
FORCEPROP 3 LASTPIN (600 4350) SIG_NAME M_J_DQS_DP<9>
J 0
(610 4360);
DISPLAY 0.659574 (610 4360);
PAINT MONO (610 4360);
DISPLAY INVISIBLE (610 4360);
FORCEPROP 1 LASTPIN (600 4350) BN 9
J 2
(650 4360);
DISPLAY 0.617021 (650 4360);
PAINT PINK (650 4360);
FORCEPROP 1 LAST PATH I24
J 2
(650 4350);
DISPLAY 0.936170 (650 4350);
PAINT GREEN (650 4350);
DISPLAY INVISIBLE (650 4350);
FORCEPROP 1 LAST HDL_TAP TRUE
J 2
(325 4225);
DISPLAY 1.234043 (325 4225);
PAINT GREEN (325 4225);
DISPLAY INVISIBLE (325 4225);
FORCEPROP 1 LAST BODY_TYPE PLUMBING
J 2
(650 4300);
DISPLAY 1.234043 (650 4300);
PAINT GREEN (650 4300);
DISPLAY INVISIBLE (650 4300);
FORCEPROP 2 LAST CDS_LIB mstr_standard
J 0
(650 4350);
DISPLAY 0.787234 (650 4350);
PAINT MONO (650 4350);
DISPLAY INVISIBLE (650 4350);
FORCEADD TAP..6
R 2
(650 4250);
FORCEPROP 3 LASTPIN (600 4250) SIG_NAME M_J_DQS_DP<8>
J 0
(610 4260);
DISPLAY 0.659574 (610 4260);
PAINT MONO (610 4260);
DISPLAY INVISIBLE (610 4260);
FORCEPROP 1 LASTPIN (600 4250) BN 8
J 2
(650 4260);
DISPLAY 0.617021 (650 4260);
PAINT PINK (650 4260);
FORCEPROP 1 LAST PATH I25
J 2
(650 4250);
DISPLAY 0.936170 (650 4250);
PAINT GREEN (650 4250);
DISPLAY INVISIBLE (650 4250);
FORCEPROP 1 LAST HDL_TAP TRUE
J 2
(325 4125);
DISPLAY 1.234043 (325 4125);
PAINT GREEN (325 4125);
DISPLAY INVISIBLE (325 4125);
FORCEPROP 1 LAST BODY_TYPE PLUMBING
J 2
(650 4200);
DISPLAY 1.234043 (650 4200);
PAINT GREEN (650 4200);
DISPLAY INVISIBLE (650 4200);
FORCEPROP 2 LAST CDS_LIB mstr_standard
J 0
(650 4250);
DISPLAY 0.787234 (650 4250);
PAINT MONO (650 4250);
DISPLAY INVISIBLE (650 4250);
FORCEADD TAP..6
R 2
(650 4150);
FORCEPROP 3 LASTPIN (600 4150) SIG_NAME M_J_DQS_DP<7>
J 0
(610 4160);
DISPLAY 0.659574 (610 4160);
PAINT MONO (610 4160);
DISPLAY INVISIBLE (610 4160);
FORCEPROP 1 LASTPIN (600 4150) BN 7
J 2
(650 4160);
DISPLAY 0.617021 (650 4160);
PAINT PINK (650 4160);
FORCEPROP 1 LAST PATH I26
J 2
(650 4150);
DISPLAY 0.936170 (650 4150);
PAINT GREEN (650 4150);
DISPLAY INVISIBLE (650 4150);
FORCEPROP 1 LAST HDL_TAP TRUE
J 2
(325 4025);
DISPLAY 1.234043 (325 4025);
PAINT GREEN (325 4025);
DISPLAY INVISIBLE (325 4025);
FORCEPROP 1 LAST BODY_TYPE PLUMBING
J 2
(650 4100);
DISPLAY 1.234043 (650 4100);
PAINT GREEN (650 4100);
DISPLAY INVISIBLE (650 4100);
FORCEPROP 2 LAST CDS_LIB mstr_standard
J 0
(650 4150);
DISPLAY 0.787234 (650 4150);
PAINT MONO (650 4150);
DISPLAY INVISIBLE (650 4150);
FORCEADD TAP..6
R 2
(850 4100);
FORCEPROP 3 LASTPIN (800 4100) SIG_NAME M_J_DQS_DN<7>
J 0
(810 4110);
DISPLAY 0.659574 (810 4110);
PAINT MONO (810 4110);
DISPLAY INVISIBLE (810 4110);
FORCEPROP 1 LASTPIN (800 4100) BN 7
J 2
(850 4110);
DISPLAY 0.617021 (850 4110);
PAINT PINK (850 4110);
FORCEPROP 1 LAST PATH I27
J 2
(850 4100);
DISPLAY 0.936170 (850 4100);
PAINT GREEN (850 4100);
DISPLAY INVISIBLE (850 4100);
FORCEPROP 1 LAST HDL_TAP TRUE
J 2
(525 3975);
DISPLAY 1.234043 (525 3975);
PAINT GREEN (525 3975);
DISPLAY INVISIBLE (525 3975);
FORCEPROP 1 LAST BODY_TYPE PLUMBING
J 2
(850 4050);
DISPLAY 1.234043 (850 4050);
PAINT GREEN (850 4050);
DISPLAY INVISIBLE (850 4050);
FORCEPROP 2 LAST CDS_LIB mstr_standard
J 0
(850 4100);
DISPLAY 0.787234 (850 4100);
PAINT MONO (850 4100);
DISPLAY INVISIBLE (850 4100);
FORCEADD TAP..6
R 2
(850 4000);
FORCEPROP 3 LASTPIN (800 4000) SIG_NAME M_J_DQS_DN<6>
J 0
(810 4010);
DISPLAY 0.659574 (810 4010);
PAINT MONO (810 4010);
DISPLAY INVISIBLE (810 4010);
FORCEPROP 1 LASTPIN (800 4000) BN 6
J 2
(850 4010);
DISPLAY 0.617021 (850 4010);
PAINT PINK (850 4010);
FORCEPROP 1 LAST PATH I28
J 2
(850 4000);
DISPLAY 0.936170 (850 4000);
PAINT GREEN (850 4000);
DISPLAY INVISIBLE (850 4000);
FORCEPROP 1 LAST HDL_TAP TRUE
J 2
(525 3875);
DISPLAY 1.234043 (525 3875);
PAINT GREEN (525 3875);
DISPLAY INVISIBLE (525 3875);
FORCEPROP 1 LAST BODY_TYPE PLUMBING
J 2
(850 3950);
DISPLAY 1.234043 (850 3950);
PAINT GREEN (850 3950);
DISPLAY INVISIBLE (850 3950);
FORCEPROP 2 LAST CDS_LIB mstr_standard
J 0
(850 4000);
DISPLAY 0.787234 (850 4000);
PAINT MONO (850 4000);
DISPLAY INVISIBLE (850 4000);
FORCEADD TAP..6
R 2
(850 3900);
FORCEPROP 3 LASTPIN (800 3900) SIG_NAME M_J_DQS_DN<5>
J 0
(810 3910);
DISPLAY 0.659574 (810 3910);
PAINT MONO (810 3910);
DISPLAY INVISIBLE (810 3910);
FORCEPROP 1 LASTPIN (800 3900) BN 5
J 2
(850 3910);
DISPLAY 0.617021 (850 3910);
PAINT PINK (850 3910);
FORCEPROP 1 LAST PATH I29
J 2
(850 3900);
DISPLAY 0.936170 (850 3900);
PAINT GREEN (850 3900);
DISPLAY INVISIBLE (850 3900);
FORCEPROP 1 LAST HDL_TAP TRUE
J 2
(525 3775);
DISPLAY 1.234043 (525 3775);
PAINT GREEN (525 3775);
DISPLAY INVISIBLE (525 3775);
FORCEPROP 1 LAST BODY_TYPE PLUMBING
J 2
(850 3850);
DISPLAY 1.234043 (850 3850);
PAINT GREEN (850 3850);
DISPLAY INVISIBLE (850 3850);
FORCEPROP 2 LAST CDS_LIB mstr_standard
J 0
(850 3900);
DISPLAY 0.787234 (850 3900);
PAINT MONO (850 3900);
DISPLAY INVISIBLE (850 3900);
FORCEADD TAP..6
R 2
(850 5100);
FORCEPROP 3 LASTPIN (800 5100) SIG_NAME M_J_DQS_DN<17>
J 0
(810 5110);
DISPLAY 0.659574 (810 5110);
PAINT MONO (810 5110);
DISPLAY INVISIBLE (810 5110);
FORCEPROP 1 LASTPIN (800 5100) BN 17
J 2
(850 5110);
DISPLAY 0.617021 (850 5110);
PAINT PINK (850 5110);
FORCEPROP 1 LAST PATH I3
J 2
(850 5100);
DISPLAY 0.936170 (850 5100);
PAINT GREEN (850 5100);
DISPLAY INVISIBLE (850 5100);
FORCEPROP 1 LAST HDL_TAP TRUE
J 2
(525 4975);
DISPLAY 1.234043 (525 4975);
PAINT GREEN (525 4975);
DISPLAY INVISIBLE (525 4975);
FORCEPROP 1 LAST BODY_TYPE PLUMBING
J 2
(850 5050);
DISPLAY 1.234043 (850 5050);
PAINT GREEN (850 5050);
DISPLAY INVISIBLE (850 5050);
FORCEPROP 2 LAST CDS_LIB mstr_standard
J 2
(850 5100);
DISPLAY 0.787234 (850 5100);
PAINT MONO (850 5100);
DISPLAY INVISIBLE (850 5100);
FORCEADD TAP..6
R 2
(850 3700);
FORCEPROP 3 LASTPIN (800 3700) SIG_NAME M_J_DQS_DN<3>
J 0
(810 3710);
DISPLAY 0.659574 (810 3710);
PAINT MONO (810 3710);
DISPLAY INVISIBLE (810 3710);
FORCEPROP 1 LASTPIN (800 3700) BN 3
J 2
(850 3710);
DISPLAY 0.617021 (850 3710);
PAINT PINK (850 3710);
FORCEPROP 1 LAST PATH I30
J 2
(850 3700);
DISPLAY 0.936170 (850 3700);
PAINT GREEN (850 3700);
DISPLAY INVISIBLE (850 3700);
FORCEPROP 1 LAST HDL_TAP TRUE
J 2
(525 3575);
DISPLAY 1.234043 (525 3575);
PAINT GREEN (525 3575);
DISPLAY INVISIBLE (525 3575);
FORCEPROP 1 LAST BODY_TYPE PLUMBING
J 2
(850 3650);
DISPLAY 1.234043 (850 3650);
PAINT GREEN (850 3650);
DISPLAY INVISIBLE (850 3650);
FORCEPROP 2 LAST CDS_LIB mstr_standard
J 0
(850 3700);
DISPLAY 0.787234 (850 3700);
PAINT MONO (850 3700);
DISPLAY INVISIBLE (850 3700);
FORCEADD TAP..6
R 2
(850 3800);
FORCEPROP 3 LASTPIN (800 3800) SIG_NAME M_J_DQS_DN<4>
J 0
(810 3810);
DISPLAY 0.659574 (810 3810);
PAINT MONO (810 3810);
DISPLAY INVISIBLE (810 3810);
FORCEPROP 1 LASTPIN (800 3800) BN 4
J 2
(850 3810);
DISPLAY 0.617021 (850 3810);
PAINT PINK (850 3810);
FORCEPROP 1 LAST PATH I31
J 2
(850 3800);
DISPLAY 0.936170 (850 3800);
PAINT GREEN (850 3800);
DISPLAY INVISIBLE (850 3800);
FORCEPROP 1 LAST HDL_TAP TRUE
J 2
(525 3675);
DISPLAY 1.234043 (525 3675);
PAINT GREEN (525 3675);
DISPLAY INVISIBLE (525 3675);
FORCEPROP 1 LAST BODY_TYPE PLUMBING
J 2
(850 3750);
DISPLAY 1.234043 (850 3750);
PAINT GREEN (850 3750);
DISPLAY INVISIBLE (850 3750);
FORCEPROP 2 LAST CDS_LIB mstr_standard
J 0
(850 3800);
DISPLAY 0.787234 (850 3800);
PAINT MONO (850 3800);
DISPLAY INVISIBLE (850 3800);
FORCEADD TAP..6
R 2
(650 4050);
FORCEPROP 3 LASTPIN (600 4050) SIG_NAME M_J_DQS_DP<6>
J 0
(610 4060);
DISPLAY 0.659574 (610 4060);
PAINT MONO (610 4060);
DISPLAY INVISIBLE (610 4060);
FORCEPROP 1 LASTPIN (600 4050) BN 6
J 2
(650 4060);
DISPLAY 0.617021 (650 4060);
PAINT PINK (650 4060);
FORCEPROP 1 LAST PATH I32
J 2
(650 4050);
DISPLAY 0.936170 (650 4050);
PAINT GREEN (650 4050);
DISPLAY INVISIBLE (650 4050);
FORCEPROP 1 LAST HDL_TAP TRUE
J 2
(325 3925);
DISPLAY 1.234043 (325 3925);
PAINT GREEN (325 3925);
DISPLAY INVISIBLE (325 3925);
FORCEPROP 1 LAST BODY_TYPE PLUMBING
J 2
(650 4000);
DISPLAY 1.234043 (650 4000);
PAINT GREEN (650 4000);
DISPLAY INVISIBLE (650 4000);
FORCEPROP 2 LAST CDS_LIB mstr_standard
J 0
(650 4050);
DISPLAY 0.787234 (650 4050);
PAINT MONO (650 4050);
DISPLAY INVISIBLE (650 4050);
FORCEADD TAP..6
R 2
(650 3950);
FORCEPROP 3 LASTPIN (600 3950) SIG_NAME M_J_DQS_DP<5>
J 0
(610 3960);
DISPLAY 0.659574 (610 3960);
PAINT MONO (610 3960);
DISPLAY INVISIBLE (610 3960);
FORCEPROP 1 LASTPIN (600 3950) BN 5
J 2
(650 3960);
DISPLAY 0.617021 (650 3960);
PAINT PINK (650 3960);
FORCEPROP 1 LAST PATH I33
J 2
(650 3950);
DISPLAY 0.936170 (650 3950);
PAINT GREEN (650 3950);
DISPLAY INVISIBLE (650 3950);
FORCEPROP 1 LAST HDL_TAP TRUE
J 2
(325 3825);
DISPLAY 1.234043 (325 3825);
PAINT GREEN (325 3825);
DISPLAY INVISIBLE (325 3825);
FORCEPROP 1 LAST BODY_TYPE PLUMBING
J 2
(650 3900);
DISPLAY 1.234043 (650 3900);
PAINT GREEN (650 3900);
DISPLAY INVISIBLE (650 3900);
FORCEPROP 2 LAST CDS_LIB mstr_standard
J 0
(650 3950);
DISPLAY 0.787234 (650 3950);
PAINT MONO (650 3950);
DISPLAY INVISIBLE (650 3950);
FORCEADD TAP..6
R 2
(650 3850);
FORCEPROP 3 LASTPIN (600 3850) SIG_NAME M_J_DQS_DP<4>
J 0
(610 3860);
DISPLAY 0.659574 (610 3860);
PAINT MONO (610 3860);
DISPLAY INVISIBLE (610 3860);
FORCEPROP 1 LASTPIN (600 3850) BN 4
J 2
(650 3860);
DISPLAY 0.617021 (650 3860);
PAINT PINK (650 3860);
FORCEPROP 1 LAST PATH I34
J 2
(650 3850);
DISPLAY 0.936170 (650 3850);
PAINT GREEN (650 3850);
DISPLAY INVISIBLE (650 3850);
FORCEPROP 1 LAST HDL_TAP TRUE
J 2
(325 3725);
DISPLAY 1.234043 (325 3725);
PAINT GREEN (325 3725);
DISPLAY INVISIBLE (325 3725);
FORCEPROP 1 LAST BODY_TYPE PLUMBING
J 2
(650 3800);
DISPLAY 1.234043 (650 3800);
PAINT GREEN (650 3800);
DISPLAY INVISIBLE (650 3800);
FORCEPROP 2 LAST CDS_LIB mstr_standard
J 0
(650 3850);
DISPLAY 0.787234 (650 3850);
PAINT MONO (650 3850);
DISPLAY INVISIBLE (650 3850);
FORCEADD TAP..6
R 2
(650 3750);
FORCEPROP 3 LASTPIN (600 3750) SIG_NAME M_J_DQS_DP<3>
J 0
(610 3760);
DISPLAY 0.659574 (610 3760);
PAINT MONO (610 3760);
DISPLAY INVISIBLE (610 3760);
FORCEPROP 1 LASTPIN (600 3750) BN 3
J 2
(650 3760);
DISPLAY 0.617021 (650 3760);
PAINT PINK (650 3760);
FORCEPROP 1 LAST PATH I35
J 2
(650 3750);
DISPLAY 0.936170 (650 3750);
PAINT GREEN (650 3750);
DISPLAY INVISIBLE (650 3750);
FORCEPROP 1 LAST HDL_TAP TRUE
J 2
(325 3625);
DISPLAY 1.234043 (325 3625);
PAINT GREEN (325 3625);
DISPLAY INVISIBLE (325 3625);
FORCEPROP 1 LAST BODY_TYPE PLUMBING
J 2
(650 3700);
DISPLAY 1.234043 (650 3700);
PAINT GREEN (650 3700);
DISPLAY INVISIBLE (650 3700);
FORCEPROP 2 LAST CDS_LIB mstr_standard
J 0
(650 3750);
DISPLAY 0.787234 (650 3750);
PAINT MONO (650 3750);
DISPLAY INVISIBLE (650 3750);
FORCEADD TAP..6
R 2
(650 3650);
FORCEPROP 3 LASTPIN (600 3650) SIG_NAME M_J_DQS_DP<2>
J 0
(610 3660);
DISPLAY 0.659574 (610 3660);
PAINT MONO (610 3660);
DISPLAY INVISIBLE (610 3660);
FORCEPROP 1 LASTPIN (600 3650) BN 2
J 2
(650 3660);
DISPLAY 0.617021 (650 3660);
PAINT PINK (650 3660);
FORCEPROP 1 LAST PATH I36
J 2
(650 3650);
DISPLAY 0.936170 (650 3650);
PAINT GREEN (650 3650);
DISPLAY INVISIBLE (650 3650);
FORCEPROP 1 LAST HDL_TAP TRUE
J 2
(325 3525);
DISPLAY 1.234043 (325 3525);
PAINT GREEN (325 3525);
DISPLAY INVISIBLE (325 3525);
FORCEPROP 1 LAST BODY_TYPE PLUMBING
J 2
(650 3600);
DISPLAY 1.234043 (650 3600);
PAINT GREEN (650 3600);
DISPLAY INVISIBLE (650 3600);
FORCEPROP 2 LAST CDS_LIB mstr_standard
J 0
(650 3650);
DISPLAY 0.787234 (650 3650);
PAINT MONO (650 3650);
DISPLAY INVISIBLE (650 3650);
FORCEADD TAP..6
R 2
(850 3500);
FORCEPROP 3 LASTPIN (800 3500) SIG_NAME M_J_DQS_DN<1>
J 0
(810 3510);
DISPLAY 0.659574 (810 3510);
PAINT MONO (810 3510);
DISPLAY INVISIBLE (810 3510);
FORCEPROP 1 LASTPIN (800 3500) BN 1
J 2
(850 3510);
DISPLAY 0.617021 (850 3510);
PAINT PINK (850 3510);
FORCEPROP 1 LAST PATH I37
J 2
(850 3500);
DISPLAY 0.936170 (850 3500);
PAINT GREEN (850 3500);
DISPLAY INVISIBLE (850 3500);
FORCEPROP 1 LAST HDL_TAP TRUE
J 2
(525 3375);
DISPLAY 1.234043 (525 3375);
PAINT GREEN (525 3375);
DISPLAY INVISIBLE (525 3375);
FORCEPROP 1 LAST BODY_TYPE PLUMBING
J 2
(850 3450);
DISPLAY 1.234043 (850 3450);
PAINT GREEN (850 3450);
DISPLAY INVISIBLE (850 3450);
FORCEPROP 2 LAST CDS_LIB mstr_standard
J 0
(850 3500);
DISPLAY 0.787234 (850 3500);
PAINT MONO (850 3500);
DISPLAY INVISIBLE (850 3500);
FORCEADD TAP..6
R 2
(850 3600);
FORCEPROP 3 LASTPIN (800 3600) SIG_NAME M_J_DQS_DN<2>
J 0
(810 3610);
DISPLAY 0.659574 (810 3610);
PAINT MONO (810 3610);
DISPLAY INVISIBLE (810 3610);
FORCEPROP 1 LASTPIN (800 3600) BN 2
J 2
(850 3610);
DISPLAY 0.617021 (850 3610);
PAINT PINK (850 3610);
FORCEPROP 1 LAST PATH I38
J 2
(850 3600);
DISPLAY 0.936170 (850 3600);
PAINT GREEN (850 3600);
DISPLAY INVISIBLE (850 3600);
FORCEPROP 1 LAST HDL_TAP TRUE
J 2
(525 3475);
DISPLAY 1.234043 (525 3475);
PAINT GREEN (525 3475);
DISPLAY INVISIBLE (525 3475);
FORCEPROP 1 LAST BODY_TYPE PLUMBING
J 2
(850 3550);
DISPLAY 1.234043 (850 3550);
PAINT GREEN (850 3550);
DISPLAY INVISIBLE (850 3550);
FORCEPROP 2 LAST CDS_LIB mstr_standard
J 0
(850 3600);
DISPLAY 0.787234 (850 3600);
PAINT MONO (850 3600);
DISPLAY INVISIBLE (850 3600);
FORCEADD TAP..6
R 2
(850 3400);
FORCEPROP 3 LASTPIN (800 3400) SIG_NAME M_J_DQS_DN<0>
J 0
(810 3410);
DISPLAY 0.659574 (810 3410);
PAINT MONO (810 3410);
DISPLAY INVISIBLE (810 3410);
FORCEPROP 1 LASTPIN (800 3400) BN 0
J 2
(850 3410);
DISPLAY 0.617021 (850 3410);
PAINT PINK (850 3410);
FORCEPROP 1 LAST PATH I39
J 2
(850 3400);
DISPLAY 0.936170 (850 3400);
PAINT GREEN (850 3400);
DISPLAY INVISIBLE (850 3400);
FORCEPROP 1 LAST HDL_TAP TRUE
J 2
(525 3275);
DISPLAY 1.234043 (525 3275);
PAINT GREEN (525 3275);
DISPLAY INVISIBLE (525 3275);
FORCEPROP 1 LAST BODY_TYPE PLUMBING
J 2
(850 3350);
DISPLAY 1.234043 (850 3350);
PAINT GREEN (850 3350);
DISPLAY INVISIBLE (850 3350);
FORCEPROP 2 LAST CDS_LIB mstr_standard
J 0
(850 3400);
DISPLAY 0.787234 (850 3400);
PAINT MONO (850 3400);
DISPLAY INVISIBLE (850 3400);
FORCEADD TAP..6
R 2
(850 5000);
FORCEPROP 3 LASTPIN (800 5000) SIG_NAME M_J_DQS_DN<16>
J 0
(810 5010);
DISPLAY 0.659574 (810 5010);
PAINT MONO (810 5010);
DISPLAY INVISIBLE (810 5010);
FORCEPROP 1 LASTPIN (800 5000) BN 16
J 2
(850 5010);
DISPLAY 0.617021 (850 5010);
PAINT PINK (850 5010);
FORCEPROP 1 LAST PATH I4
J 2
(850 5000);
DISPLAY 0.936170 (850 5000);
PAINT GREEN (850 5000);
DISPLAY INVISIBLE (850 5000);
FORCEPROP 1 LAST HDL_TAP TRUE
J 2
(525 4875);
DISPLAY 1.234043 (525 4875);
PAINT GREEN (525 4875);
DISPLAY INVISIBLE (525 4875);
FORCEPROP 1 LAST BODY_TYPE PLUMBING
J 2
(850 4950);
DISPLAY 1.234043 (850 4950);
PAINT GREEN (850 4950);
DISPLAY INVISIBLE (850 4950);
FORCEPROP 2 LAST CDS_LIB mstr_standard
J 0
(850 5000);
DISPLAY 0.787234 (850 5000);
PAINT MONO (850 5000);
DISPLAY INVISIBLE (850 5000);
FORCEADD TAP..6
R 2
(650 3550);
FORCEPROP 3 LASTPIN (600 3550) SIG_NAME M_J_DQS_DP<1>
J 0
(610 3560);
DISPLAY 0.659574 (610 3560);
PAINT MONO (610 3560);
DISPLAY INVISIBLE (610 3560);
FORCEPROP 1 LASTPIN (600 3550) BN 1
J 2
(650 3560);
DISPLAY 0.617021 (650 3560);
PAINT PINK (650 3560);
FORCEPROP 1 LAST PATH I40
J 2
(650 3550);
DISPLAY 0.936170 (650 3550);
PAINT GREEN (650 3550);
DISPLAY INVISIBLE (650 3550);
FORCEPROP 1 LAST HDL_TAP TRUE
J 2
(325 3425);
DISPLAY 1.234043 (325 3425);
PAINT GREEN (325 3425);
DISPLAY INVISIBLE (325 3425);
FORCEPROP 1 LAST BODY_TYPE PLUMBING
J 2
(650 3500);
DISPLAY 1.234043 (650 3500);
PAINT GREEN (650 3500);
DISPLAY INVISIBLE (650 3500);
FORCEPROP 2 LAST CDS_LIB mstr_standard
J 0
(650 3550);
DISPLAY 0.787234 (650 3550);
PAINT MONO (650 3550);
DISPLAY INVISIBLE (650 3550);
FORCEADD TAP..6
R 2
(650 3450);
FORCEPROP 3 LASTPIN (600 3450) SIG_NAME M_J_DQS_DP<0>
J 0
(610 3460);
DISPLAY 0.659574 (610 3460);
PAINT MONO (610 3460);
DISPLAY INVISIBLE (610 3460);
FORCEPROP 1 LASTPIN (600 3450) BN 0
J 2
(650 3460);
DISPLAY 0.617021 (650 3460);
PAINT PINK (650 3460);
FORCEPROP 1 LAST PATH I41
J 2
(650 3450);
DISPLAY 0.936170 (650 3450);
PAINT GREEN (650 3450);
DISPLAY INVISIBLE (650 3450);
FORCEPROP 1 LAST HDL_TAP TRUE
J 2
(325 3325);
DISPLAY 1.234043 (325 3325);
PAINT GREEN (325 3325);
DISPLAY INVISIBLE (325 3325);
FORCEPROP 1 LAST BODY_TYPE PLUMBING
J 2
(650 3400);
DISPLAY 1.234043 (650 3400);
PAINT GREEN (650 3400);
DISPLAY INVISIBLE (650 3400);
FORCEPROP 2 LAST CDS_LIB mstr_standard
J 0
(650 3450);
DISPLAY 0.787234 (650 3450);
PAINT MONO (650 3450);
DISPLAY INVISIBLE (650 3450);
FORCEADD GND..1
R 2
(1050 1050);
FORCEPROP 3 LASTPIN (1050 1100) SIG_NAME GND\g
J 0
(1060 1110);
DISPLAY 0.659574 (1060 1110);
PAINT MONO (1060 1110);
DISPLAY INVISIBLE (1060 1110);
FORCEPROP 1 LAST HDL_POWER GND
J 2
(1050 1200);
DISPLAY 0.553191 (1050 1200);
PAINT GREEN (1050 1200);
DISPLAY INVISIBLE (1050 1200);
FORCEPROP 2 LAST ROOM DDR4_CH_J
J 0
(1050 1055);
PAINT ORANGE (1050 1055);
DISPLAY INVISIBLE (1050 1055);
FORCEPROP 1 LAST PATH I44
J 2
(975 1050);
DISPLAY 0.936170 (975 1050);
PAINT GREEN (975 1050);
DISPLAY INVISIBLE (975 1050);
FORCEPROP 1 LAST BODY_TYPE PLUMBING
J 2
(1095 1007);
DISPLAY 0.340426 (1095 1007);
PAINT GREEN (1095 1007);
DISPLAY INVISIBLE (1095 1007);
FORCEPROP 2 LAST BOM_COST MEM
J 0
(1050 1055);
PAINT ORANGE (1050 1055);
DISPLAY INVISIBLE (1050 1055);
FORCEPROP 2 LAST CDS_LIB mstr_symbols
J 0
(1050 1050);
DISPLAY 0.787234 (1050 1050);
PAINT MONO (1050 1050);
DISPLAY INVISIBLE (1050 1050);
FORCEPROP 1 LAST SIZE 1B
J 2
(975 1000);
DISPLAY 1.170213 (975 1000);
PAINT GREEN (975 1000);
DISPLAY INVISIBLE (975 1000);
FORCEPROP 1 LAST VOLTAGE 0
J 0
(1050 1050);
PAINT SKYBLUE (1050 1050);
DISPLAY INVISIBLE (1050 1050);
FORCEADD OFFPAGE..3
(-1200 4850);
FORCEPROP 2 LAST $XR1 81 
J 0
(-896 4850);
DISPLAY 0.638298 (-896 4850);
PAINT MONO (-896 4850);
FORCEPROP 2 LAST $XR0 59 
J 0
(-986 4850);
DISPLAY 0.638298 (-986 4850);
PAINT MONO (-986 4850);
FORCEPROP 2 LAST PATH I45
J 0
(-1000 4925);
DISPLAY 0.787234 (-1000 4925);
PAINT MONO (-1000 4925);
DISPLAY INVISIBLE (-1000 4925);
FORCEPROP 1 LAST COMMENT_BODY TRUE
J 0
(-1250 4750);
DISPLAY 0.936170 (-1250 4750);
PAINT GREEN (-1250 4750);
DISPLAY INVISIBLE (-1250 4750);
FORCEPROP 1 LAST OFFPAGE TRUE
J 0
(-875 4725);
DISPLAY 0.936170 (-875 4725);
PAINT GREEN (-875 4725);
DISPLAY INVISIBLE (-875 4725);
FORCEPROP 2 LAST CDS_LIB mstr_standard
J 0
(-1200 4850);
DISPLAY 0.787234 (-1200 4850);
PAINT MONO (-1200 4850);
DISPLAY INVISIBLE (-1200 4850);
FORCEADD TAP..6
R 2
(-1750 4750);
FORCEPROP 3 LASTPIN (-1800 4750) SIG_NAME M_J_DQ<62>
J 0
(-1790 4760);
DISPLAY 0.659574 (-1790 4760);
PAINT MONO (-1790 4760);
DISPLAY INVISIBLE (-1790 4760);
FORCEPROP 1 LASTPIN (-1800 4750) BN 62
J 2
(-1750 4760);
DISPLAY 0.617021 (-1750 4760);
PAINT PINK (-1750 4760);
FORCEPROP 1 LAST PATH I46
J 2
(-1750 4750);
DISPLAY 0.936170 (-1750 4750);
PAINT GREEN (-1750 4750);
DISPLAY INVISIBLE (-1750 4750);
FORCEPROP 1 LAST HDL_TAP TRUE
J 2
(-2075 4625);
DISPLAY 1.234043 (-2075 4625);
PAINT GREEN (-2075 4625);
DISPLAY INVISIBLE (-2075 4625);
FORCEPROP 1 LAST BODY_TYPE PLUMBING
J 2
(-1750 4700);
DISPLAY 1.234043 (-1750 4700);
PAINT GREEN (-1750 4700);
DISPLAY INVISIBLE (-1750 4700);
FORCEPROP 2 LAST CDS_LIB mstr_standard
J 2
(-1750 4750);
DISPLAY 0.787234 (-1750 4750);
PAINT MONO (-1750 4750);
DISPLAY INVISIBLE (-1750 4750);
FORCEADD TAP..6
R 2
(-1750 4800);
FORCEPROP 3 LASTPIN (-1800 4800) SIG_NAME M_J_DQ<63>
J 0
(-1790 4810);
DISPLAY 0.659574 (-1790 4810);
PAINT MONO (-1790 4810);
DISPLAY INVISIBLE (-1790 4810);
FORCEPROP 1 LASTPIN (-1800 4800) BN 63
J 2
(-1750 4810);
DISPLAY 0.617021 (-1750 4810);
PAINT PINK (-1750 4810);
FORCEPROP 1 LAST PATH I47
J 2
(-1750 4800);
DISPLAY 0.936170 (-1750 4800);
PAINT GREEN (-1750 4800);
DISPLAY INVISIBLE (-1750 4800);
FORCEPROP 1 LAST HDL_TAP TRUE
J 2
(-2075 4675);
DISPLAY 1.234043 (-2075 4675);
PAINT GREEN (-2075 4675);
DISPLAY INVISIBLE (-2075 4675);
FORCEPROP 1 LAST BODY_TYPE PLUMBING
J 2
(-1750 4750);
DISPLAY 1.234043 (-1750 4750);
PAINT GREEN (-1750 4750);
DISPLAY INVISIBLE (-1750 4750);
FORCEPROP 2 LAST CDS_LIB mstr_standard
J 2
(-1750 4800);
DISPLAY 0.787234 (-1750 4800);
PAINT MONO (-1750 4800);
DISPLAY INVISIBLE (-1750 4800);
FORCEADD TAP..6
R 2
(-1750 4650);
FORCEPROP 3 LASTPIN (-1800 4650) SIG_NAME M_J_DQ<60>
J 0
(-1790 4660);
DISPLAY 0.659574 (-1790 4660);
PAINT MONO (-1790 4660);
DISPLAY INVISIBLE (-1790 4660);
FORCEPROP 1 LASTPIN (-1800 4650) BN 60
J 2
(-1750 4660);
DISPLAY 0.617021 (-1750 4660);
PAINT PINK (-1750 4660);
FORCEPROP 1 LAST PATH I48
J 2
(-1750 4650);
DISPLAY 0.936170 (-1750 4650);
PAINT GREEN (-1750 4650);
DISPLAY INVISIBLE (-1750 4650);
FORCEPROP 1 LAST HDL_TAP TRUE
J 2
(-2075 4525);
DISPLAY 1.234043 (-2075 4525);
PAINT GREEN (-2075 4525);
DISPLAY INVISIBLE (-2075 4525);
FORCEPROP 1 LAST BODY_TYPE PLUMBING
J 2
(-1750 4600);
DISPLAY 1.234043 (-1750 4600);
PAINT GREEN (-1750 4600);
DISPLAY INVISIBLE (-1750 4600);
FORCEPROP 2 LAST CDS_LIB mstr_standard
J 2
(-1750 4650);
DISPLAY 0.787234 (-1750 4650);
PAINT MONO (-1750 4650);
DISPLAY INVISIBLE (-1750 4650);
FORCEADD TAP..6
R 2
(-1750 4700);
FORCEPROP 3 LASTPIN (-1800 4700) SIG_NAME M_J_DQ<61>
J 0
(-1790 4710);
DISPLAY 0.659574 (-1790 4710);
PAINT MONO (-1790 4710);
DISPLAY INVISIBLE (-1790 4710);
FORCEPROP 1 LASTPIN (-1800 4700) BN 61
J 2
(-1750 4710);
DISPLAY 0.617021 (-1750 4710);
PAINT PINK (-1750 4710);
FORCEPROP 1 LAST PATH I49
J 2
(-1750 4700);
DISPLAY 0.936170 (-1750 4700);
PAINT GREEN (-1750 4700);
DISPLAY INVISIBLE (-1750 4700);
FORCEPROP 1 LAST HDL_TAP TRUE
J 2
(-2075 4575);
DISPLAY 1.234043 (-2075 4575);
PAINT GREEN (-2075 4575);
DISPLAY INVISIBLE (-2075 4575);
FORCEPROP 1 LAST BODY_TYPE PLUMBING
J 2
(-1750 4650);
DISPLAY 1.234043 (-1750 4650);
PAINT GREEN (-1750 4650);
DISPLAY INVISIBLE (-1750 4650);
FORCEPROP 2 LAST CDS_LIB mstr_standard
J 2
(-1750 4700);
DISPLAY 0.787234 (-1750 4700);
PAINT MONO (-1750 4700);
DISPLAY INVISIBLE (-1750 4700);
FORCEADD TAP..6
R 2
(850 4900);
FORCEPROP 3 LASTPIN (800 4900) SIG_NAME M_J_DQS_DN<15>
J 0
(810 4910);
DISPLAY 0.659574 (810 4910);
PAINT MONO (810 4910);
DISPLAY INVISIBLE (810 4910);
FORCEPROP 1 LASTPIN (800 4900) BN 15
J 2
(850 4910);
DISPLAY 0.617021 (850 4910);
PAINT PINK (850 4910);
FORCEPROP 1 LAST PATH I5
J 2
(850 4900);
DISPLAY 0.936170 (850 4900);
PAINT GREEN (850 4900);
DISPLAY INVISIBLE (850 4900);
FORCEPROP 1 LAST HDL_TAP TRUE
J 2
(525 4775);
DISPLAY 1.234043 (525 4775);
PAINT GREEN (525 4775);
DISPLAY INVISIBLE (525 4775);
FORCEPROP 1 LAST BODY_TYPE PLUMBING
J 2
(850 4850);
DISPLAY 1.234043 (850 4850);
PAINT GREEN (850 4850);
DISPLAY INVISIBLE (850 4850);
FORCEPROP 2 LAST CDS_LIB mstr_standard
J 0
(850 4900);
DISPLAY 0.787234 (850 4900);
PAINT MONO (850 4900);
DISPLAY INVISIBLE (850 4900);
FORCEADD TAP..6
R 2
(-1750 4600);
FORCEPROP 3 LASTPIN (-1800 4600) SIG_NAME M_J_DQ<59>
J 0
(-1790 4610);
DISPLAY 0.659574 (-1790 4610);
PAINT MONO (-1790 4610);
DISPLAY INVISIBLE (-1790 4610);
FORCEPROP 1 LASTPIN (-1800 4600) BN 59
J 2
(-1750 4610);
DISPLAY 0.617021 (-1750 4610);
PAINT PINK (-1750 4610);
FORCEPROP 1 LAST PATH I50
J 2
(-1750 4600);
DISPLAY 0.936170 (-1750 4600);
PAINT GREEN (-1750 4600);
DISPLAY INVISIBLE (-1750 4600);
FORCEPROP 1 LAST HDL_TAP TRUE
J 2
(-2075 4475);
DISPLAY 1.234043 (-2075 4475);
PAINT GREEN (-2075 4475);
DISPLAY INVISIBLE (-2075 4475);
FORCEPROP 1 LAST BODY_TYPE PLUMBING
J 2
(-1750 4550);
DISPLAY 1.234043 (-1750 4550);
PAINT GREEN (-1750 4550);
DISPLAY INVISIBLE (-1750 4550);
FORCEPROP 2 LAST CDS_LIB mstr_standard
J 2
(-1750 4600);
DISPLAY 0.787234 (-1750 4600);
PAINT MONO (-1750 4600);
DISPLAY INVISIBLE (-1750 4600);
FORCEADD TAP..6
R 2
(-1750 4550);
FORCEPROP 3 LASTPIN (-1800 4550) SIG_NAME M_J_DQ<58>
J 0
(-1790 4560);
DISPLAY 0.659574 (-1790 4560);
PAINT MONO (-1790 4560);
DISPLAY INVISIBLE (-1790 4560);
FORCEPROP 1 LASTPIN (-1800 4550) BN 58
J 2
(-1750 4560);
DISPLAY 0.617021 (-1750 4560);
PAINT PINK (-1750 4560);
FORCEPROP 1 LAST PATH I51
J 2
(-1750 4550);
DISPLAY 0.936170 (-1750 4550);
PAINT GREEN (-1750 4550);
DISPLAY INVISIBLE (-1750 4550);
FORCEPROP 1 LAST HDL_TAP TRUE
J 2
(-2075 4425);
DISPLAY 1.234043 (-2075 4425);
PAINT GREEN (-2075 4425);
DISPLAY INVISIBLE (-2075 4425);
FORCEPROP 1 LAST BODY_TYPE PLUMBING
J 2
(-1750 4500);
DISPLAY 1.234043 (-1750 4500);
PAINT GREEN (-1750 4500);
DISPLAY INVISIBLE (-1750 4500);
FORCEPROP 2 LAST CDS_LIB mstr_standard
J 2
(-1750 4550);
DISPLAY 0.787234 (-1750 4550);
PAINT MONO (-1750 4550);
DISPLAY INVISIBLE (-1750 4550);
FORCEADD TAP..6
R 2
(-1750 4500);
FORCEPROP 3 LASTPIN (-1800 4500) SIG_NAME M_J_DQ<57>
J 0
(-1790 4510);
DISPLAY 0.659574 (-1790 4510);
PAINT MONO (-1790 4510);
DISPLAY INVISIBLE (-1790 4510);
FORCEPROP 1 LASTPIN (-1800 4500) BN 57
J 2
(-1750 4510);
DISPLAY 0.617021 (-1750 4510);
PAINT PINK (-1750 4510);
FORCEPROP 1 LAST PATH I52
J 2
(-1750 4500);
DISPLAY 0.936170 (-1750 4500);
PAINT GREEN (-1750 4500);
DISPLAY INVISIBLE (-1750 4500);
FORCEPROP 1 LAST HDL_TAP TRUE
J 2
(-2075 4375);
DISPLAY 1.234043 (-2075 4375);
PAINT GREEN (-2075 4375);
DISPLAY INVISIBLE (-2075 4375);
FORCEPROP 1 LAST BODY_TYPE PLUMBING
J 2
(-1750 4450);
DISPLAY 1.234043 (-1750 4450);
PAINT GREEN (-1750 4450);
DISPLAY INVISIBLE (-1750 4450);
FORCEPROP 2 LAST CDS_LIB mstr_standard
J 2
(-1750 4500);
DISPLAY 0.787234 (-1750 4500);
PAINT MONO (-1750 4500);
DISPLAY INVISIBLE (-1750 4500);
FORCEADD TAP..6
R 2
(-1750 4300);
FORCEPROP 3 LASTPIN (-1800 4300) SIG_NAME M_J_DQ<53>
J 0
(-1790 4310);
DISPLAY 0.659574 (-1790 4310);
PAINT MONO (-1790 4310);
DISPLAY INVISIBLE (-1790 4310);
FORCEPROP 1 LASTPIN (-1800 4300) BN 53
J 2
(-1750 4310);
DISPLAY 0.617021 (-1750 4310);
PAINT PINK (-1750 4310);
FORCEPROP 1 LAST PATH I53
J 2
(-1750 4300);
DISPLAY 0.936170 (-1750 4300);
PAINT GREEN (-1750 4300);
DISPLAY INVISIBLE (-1750 4300);
FORCEPROP 1 LAST HDL_TAP TRUE
J 2
(-2075 4175);
DISPLAY 1.234043 (-2075 4175);
PAINT GREEN (-2075 4175);
DISPLAY INVISIBLE (-2075 4175);
FORCEPROP 1 LAST BODY_TYPE PLUMBING
J 2
(-1750 4250);
DISPLAY 1.234043 (-1750 4250);
PAINT GREEN (-1750 4250);
DISPLAY INVISIBLE (-1750 4250);
FORCEPROP 2 LAST CDS_LIB mstr_standard
J 2
(-1750 4300);
DISPLAY 0.787234 (-1750 4300);
PAINT MONO (-1750 4300);
DISPLAY INVISIBLE (-1750 4300);
FORCEADD TAP..6
R 2
(-1750 4350);
FORCEPROP 3 LASTPIN (-1800 4350) SIG_NAME M_J_DQ<54>
J 0
(-1790 4360);
DISPLAY 0.659574 (-1790 4360);
PAINT MONO (-1790 4360);
DISPLAY INVISIBLE (-1790 4360);
FORCEPROP 1 LASTPIN (-1800 4350) BN 54
J 2
(-1750 4360);
DISPLAY 0.617021 (-1750 4360);
PAINT PINK (-1750 4360);
FORCEPROP 1 LAST PATH I54
J 2
(-1750 4350);
DISPLAY 0.936170 (-1750 4350);
PAINT GREEN (-1750 4350);
DISPLAY INVISIBLE (-1750 4350);
FORCEPROP 1 LAST HDL_TAP TRUE
J 2
(-2075 4225);
DISPLAY 1.234043 (-2075 4225);
PAINT GREEN (-2075 4225);
DISPLAY INVISIBLE (-2075 4225);
FORCEPROP 1 LAST BODY_TYPE PLUMBING
J 2
(-1750 4300);
DISPLAY 1.234043 (-1750 4300);
PAINT GREEN (-1750 4300);
DISPLAY INVISIBLE (-1750 4300);
FORCEPROP 2 LAST CDS_LIB mstr_standard
J 2
(-1750 4350);
DISPLAY 0.787234 (-1750 4350);
PAINT MONO (-1750 4350);
DISPLAY INVISIBLE (-1750 4350);
FORCEADD TAP..6
R 2
(-1750 4250);
FORCEPROP 3 LASTPIN (-1800 4250) SIG_NAME M_J_DQ<52>
J 0
(-1790 4260);
DISPLAY 0.659574 (-1790 4260);
PAINT MONO (-1790 4260);
DISPLAY INVISIBLE (-1790 4260);
FORCEPROP 1 LASTPIN (-1800 4250) BN 52
J 2
(-1750 4260);
DISPLAY 0.617021 (-1750 4260);
PAINT PINK (-1750 4260);
FORCEPROP 1 LAST PATH I55
J 2
(-1750 4250);
DISPLAY 0.936170 (-1750 4250);
PAINT GREEN (-1750 4250);
DISPLAY INVISIBLE (-1750 4250);
FORCEPROP 1 LAST HDL_TAP TRUE
J 2
(-2075 4125);
DISPLAY 1.234043 (-2075 4125);
PAINT GREEN (-2075 4125);
DISPLAY INVISIBLE (-2075 4125);
FORCEPROP 1 LAST BODY_TYPE PLUMBING
J 2
(-1750 4200);
DISPLAY 1.234043 (-1750 4200);
PAINT GREEN (-1750 4200);
DISPLAY INVISIBLE (-1750 4200);
FORCEPROP 2 LAST CDS_LIB mstr_standard
J 2
(-1750 4250);
DISPLAY 0.787234 (-1750 4250);
PAINT MONO (-1750 4250);
DISPLAY INVISIBLE (-1750 4250);
FORCEADD TAP..6
R 2
(-1750 4400);
FORCEPROP 3 LASTPIN (-1800 4400) SIG_NAME M_J_DQ<55>
J 0
(-1790 4410);
DISPLAY 0.659574 (-1790 4410);
PAINT MONO (-1790 4410);
DISPLAY INVISIBLE (-1790 4410);
FORCEPROP 1 LASTPIN (-1800 4400) BN 55
J 2
(-1750 4410);
DISPLAY 0.617021 (-1750 4410);
PAINT PINK (-1750 4410);
FORCEPROP 1 LAST PATH I56
J 2
(-1750 4400);
DISPLAY 0.936170 (-1750 4400);
PAINT GREEN (-1750 4400);
DISPLAY INVISIBLE (-1750 4400);
FORCEPROP 1 LAST HDL_TAP TRUE
J 2
(-2075 4275);
DISPLAY 1.234043 (-2075 4275);
PAINT GREEN (-2075 4275);
DISPLAY INVISIBLE (-2075 4275);
FORCEPROP 1 LAST BODY_TYPE PLUMBING
J 2
(-1750 4350);
DISPLAY 1.234043 (-1750 4350);
PAINT GREEN (-1750 4350);
DISPLAY INVISIBLE (-1750 4350);
FORCEPROP 2 LAST CDS_LIB mstr_standard
J 2
(-1750 4400);
DISPLAY 0.787234 (-1750 4400);
PAINT MONO (-1750 4400);
DISPLAY INVISIBLE (-1750 4400);
FORCEADD TAP..6
R 2
(-1750 4450);
FORCEPROP 3 LASTPIN (-1800 4450) SIG_NAME M_J_DQ<56>
J 0
(-1790 4460);
DISPLAY 0.659574 (-1790 4460);
PAINT MONO (-1790 4460);
DISPLAY INVISIBLE (-1790 4460);
FORCEPROP 1 LASTPIN (-1800 4450) BN 56
J 2
(-1750 4460);
DISPLAY 0.617021 (-1750 4460);
PAINT PINK (-1750 4460);
FORCEPROP 1 LAST PATH I57
J 2
(-1750 4450);
DISPLAY 0.936170 (-1750 4450);
PAINT GREEN (-1750 4450);
DISPLAY INVISIBLE (-1750 4450);
FORCEPROP 1 LAST HDL_TAP TRUE
J 2
(-2075 4325);
DISPLAY 1.234043 (-2075 4325);
PAINT GREEN (-2075 4325);
DISPLAY INVISIBLE (-2075 4325);
FORCEPROP 1 LAST BODY_TYPE PLUMBING
J 2
(-1750 4400);
DISPLAY 1.234043 (-1750 4400);
PAINT GREEN (-1750 4400);
DISPLAY INVISIBLE (-1750 4400);
FORCEPROP 2 LAST CDS_LIB mstr_standard
J 2
(-1750 4450);
DISPLAY 0.787234 (-1750 4450);
PAINT MONO (-1750 4450);
DISPLAY INVISIBLE (-1750 4450);
FORCEADD TAP..6
R 2
(-1750 4000);
FORCEPROP 3 LASTPIN (-1800 4000) SIG_NAME M_J_DQ<47>
J 0
(-1790 4010);
DISPLAY 0.659574 (-1790 4010);
PAINT MONO (-1790 4010);
DISPLAY INVISIBLE (-1790 4010);
FORCEPROP 1 LASTPIN (-1800 4000) BN 47
J 2
(-1750 4010);
DISPLAY 0.617021 (-1750 4010);
PAINT PINK (-1750 4010);
FORCEPROP 1 LAST PATH I58
J 2
(-1750 4000);
DISPLAY 0.936170 (-1750 4000);
PAINT GREEN (-1750 4000);
DISPLAY INVISIBLE (-1750 4000);
FORCEPROP 1 LAST HDL_TAP TRUE
J 2
(-2075 3875);
DISPLAY 1.234043 (-2075 3875);
PAINT GREEN (-2075 3875);
DISPLAY INVISIBLE (-2075 3875);
FORCEPROP 1 LAST BODY_TYPE PLUMBING
J 2
(-1750 3950);
DISPLAY 1.234043 (-1750 3950);
PAINT GREEN (-1750 3950);
DISPLAY INVISIBLE (-1750 3950);
FORCEPROP 2 LAST CDS_LIB mstr_standard
J 2
(-1750 4000);
DISPLAY 0.787234 (-1750 4000);
PAINT MONO (-1750 4000);
DISPLAY INVISIBLE (-1750 4000);
FORCEADD TAP..6
R 2
(-1750 4050);
FORCEPROP 3 LASTPIN (-1800 4050) SIG_NAME M_J_DQ<48>
J 0
(-1790 4060);
DISPLAY 0.659574 (-1790 4060);
PAINT MONO (-1790 4060);
DISPLAY INVISIBLE (-1790 4060);
FORCEPROP 1 LASTPIN (-1800 4050) BN 48
J 2
(-1750 4060);
DISPLAY 0.617021 (-1750 4060);
PAINT PINK (-1750 4060);
FORCEPROP 1 LAST PATH I59
J 2
(-1750 4050);
DISPLAY 0.936170 (-1750 4050);
PAINT GREEN (-1750 4050);
DISPLAY INVISIBLE (-1750 4050);
FORCEPROP 1 LAST HDL_TAP TRUE
J 2
(-2075 3925);
DISPLAY 1.234043 (-2075 3925);
PAINT GREEN (-2075 3925);
DISPLAY INVISIBLE (-2075 3925);
FORCEPROP 1 LAST BODY_TYPE PLUMBING
J 2
(-1750 4000);
DISPLAY 1.234043 (-1750 4000);
PAINT GREEN (-1750 4000);
DISPLAY INVISIBLE (-1750 4000);
FORCEPROP 2 LAST CDS_LIB mstr_standard
J 2
(-1750 4050);
DISPLAY 0.787234 (-1750 4050);
PAINT MONO (-1750 4050);
DISPLAY INVISIBLE (-1750 4050);
FORCEADD TAP..6
R 2
(850 4800);
FORCEPROP 3 LASTPIN (800 4800) SIG_NAME M_J_DQS_DN<14>
J 0
(810 4810);
DISPLAY 0.659574 (810 4810);
PAINT MONO (810 4810);
DISPLAY INVISIBLE (810 4810);
FORCEPROP 1 LASTPIN (800 4800) BN 14
J 2
(850 4810);
DISPLAY 0.617021 (850 4810);
PAINT PINK (850 4810);
FORCEPROP 1 LAST PATH I6
J 2
(850 4800);
DISPLAY 0.936170 (850 4800);
PAINT GREEN (850 4800);
DISPLAY INVISIBLE (850 4800);
FORCEPROP 1 LAST HDL_TAP TRUE
J 2
(525 4675);
DISPLAY 1.234043 (525 4675);
PAINT GREEN (525 4675);
DISPLAY INVISIBLE (525 4675);
FORCEPROP 1 LAST BODY_TYPE PLUMBING
J 2
(850 4750);
DISPLAY 1.234043 (850 4750);
PAINT GREEN (850 4750);
DISPLAY INVISIBLE (850 4750);
FORCEPROP 2 LAST CDS_LIB mstr_standard
J 0
(850 4800);
DISPLAY 0.787234 (850 4800);
PAINT MONO (850 4800);
DISPLAY INVISIBLE (850 4800);
FORCEADD TAP..6
R 2
(-1750 3950);
FORCEPROP 3 LASTPIN (-1800 3950) SIG_NAME M_J_DQ<46>
J 0
(-1790 3960);
DISPLAY 0.659574 (-1790 3960);
PAINT MONO (-1790 3960);
DISPLAY INVISIBLE (-1790 3960);
FORCEPROP 1 LASTPIN (-1800 3950) BN 46
J 2
(-1750 3960);
DISPLAY 0.617021 (-1750 3960);
PAINT PINK (-1750 3960);
FORCEPROP 1 LAST PATH I60
J 2
(-1750 3950);
DISPLAY 0.936170 (-1750 3950);
PAINT GREEN (-1750 3950);
DISPLAY INVISIBLE (-1750 3950);
FORCEPROP 1 LAST HDL_TAP TRUE
J 2
(-2075 3825);
DISPLAY 1.234043 (-2075 3825);
PAINT GREEN (-2075 3825);
DISPLAY INVISIBLE (-2075 3825);
FORCEPROP 1 LAST BODY_TYPE PLUMBING
J 2
(-1750 3900);
DISPLAY 1.234043 (-1750 3900);
PAINT GREEN (-1750 3900);
DISPLAY INVISIBLE (-1750 3900);
FORCEPROP 2 LAST CDS_LIB mstr_standard
J 2
(-1750 3950);
DISPLAY 0.787234 (-1750 3950);
PAINT MONO (-1750 3950);
DISPLAY INVISIBLE (-1750 3950);
FORCEADD TAP..6
R 2
(-1750 4100);
FORCEPROP 3 LASTPIN (-1800 4100) SIG_NAME M_J_DQ<49>
J 0
(-1790 4110);
DISPLAY 0.659574 (-1790 4110);
PAINT MONO (-1790 4110);
DISPLAY INVISIBLE (-1790 4110);
FORCEPROP 1 LASTPIN (-1800 4100) BN 49
J 2
(-1750 4110);
DISPLAY 0.617021 (-1750 4110);
PAINT PINK (-1750 4110);
FORCEPROP 1 LAST PATH I61
J 2
(-1750 4100);
DISPLAY 0.936170 (-1750 4100);
PAINT GREEN (-1750 4100);
DISPLAY INVISIBLE (-1750 4100);
FORCEPROP 1 LAST HDL_TAP TRUE
J 2
(-2075 3975);
DISPLAY 1.234043 (-2075 3975);
PAINT GREEN (-2075 3975);
DISPLAY INVISIBLE (-2075 3975);
FORCEPROP 1 LAST BODY_TYPE PLUMBING
J 2
(-1750 4050);
DISPLAY 1.234043 (-1750 4050);
PAINT GREEN (-1750 4050);
DISPLAY INVISIBLE (-1750 4050);
FORCEPROP 2 LAST CDS_LIB mstr_standard
J 2
(-1750 4100);
DISPLAY 0.787234 (-1750 4100);
PAINT MONO (-1750 4100);
DISPLAY INVISIBLE (-1750 4100);
FORCEADD TAP..6
R 2
(-1750 4150);
FORCEPROP 3 LASTPIN (-1800 4150) SIG_NAME M_J_DQ<50>
J 0
(-1790 4160);
DISPLAY 0.659574 (-1790 4160);
PAINT MONO (-1790 4160);
DISPLAY INVISIBLE (-1790 4160);
FORCEPROP 1 LASTPIN (-1800 4150) BN 50
J 2
(-1750 4160);
DISPLAY 0.617021 (-1750 4160);
PAINT PINK (-1750 4160);
FORCEPROP 1 LAST PATH I62
J 2
(-1750 4150);
DISPLAY 0.936170 (-1750 4150);
PAINT GREEN (-1750 4150);
DISPLAY INVISIBLE (-1750 4150);
FORCEPROP 1 LAST HDL_TAP TRUE
J 2
(-2075 4025);
DISPLAY 1.234043 (-2075 4025);
PAINT GREEN (-2075 4025);
DISPLAY INVISIBLE (-2075 4025);
FORCEPROP 1 LAST BODY_TYPE PLUMBING
J 2
(-1750 4100);
DISPLAY 1.234043 (-1750 4100);
PAINT GREEN (-1750 4100);
DISPLAY INVISIBLE (-1750 4100);
FORCEPROP 2 LAST CDS_LIB mstr_standard
J 2
(-1750 4150);
DISPLAY 0.787234 (-1750 4150);
PAINT MONO (-1750 4150);
DISPLAY INVISIBLE (-1750 4150);
FORCEADD TAP..6
R 2
(-1750 4200);
FORCEPROP 3 LASTPIN (-1800 4200) SIG_NAME M_J_DQ<51>
J 0
(-1790 4210);
DISPLAY 0.659574 (-1790 4210);
PAINT MONO (-1790 4210);
DISPLAY INVISIBLE (-1790 4210);
FORCEPROP 1 LASTPIN (-1800 4200) BN 51
J 2
(-1750 4210);
DISPLAY 0.617021 (-1750 4210);
PAINT PINK (-1750 4210);
FORCEPROP 1 LAST PATH I63
J 2
(-1750 4200);
DISPLAY 0.936170 (-1750 4200);
PAINT GREEN (-1750 4200);
DISPLAY INVISIBLE (-1750 4200);
FORCEPROP 1 LAST HDL_TAP TRUE
J 2
(-2075 4075);
DISPLAY 1.234043 (-2075 4075);
PAINT GREEN (-2075 4075);
DISPLAY INVISIBLE (-2075 4075);
FORCEPROP 1 LAST BODY_TYPE PLUMBING
J 2
(-1750 4150);
DISPLAY 1.234043 (-1750 4150);
PAINT GREEN (-1750 4150);
DISPLAY INVISIBLE (-1750 4150);
FORCEPROP 2 LAST CDS_LIB mstr_standard
J 2
(-1750 4200);
DISPLAY 0.787234 (-1750 4200);
PAINT MONO (-1750 4200);
DISPLAY INVISIBLE (-1750 4200);
FORCEADD SCONN288_H44441003..2
(-50 4300);
FORCEPROP 2 LASTPIN (400 3950) $PN 256
J 0
(410 3960);
DISPLAY 0.617021 (410 3960);
PAINT ORANGE (410 3960);
FORCEPROP 0 LAST BOM_SS NOPOP
J 0
(-276 5378);
DISPLAY 1.021277 (-276 5378);
PAINT BROWN (-276 5378);
DISPLAY BOTH (-276 5378);
FORCEPROP 2 LASTPIN (400 4100) $PN 277
J 0
(410 4110);
DISPLAY 0.617021 (410 4110);
PAINT ORANGE (410 4110);
FORCEPROP 2 LASTPIN (400 3650) $PN 175
J 0
(410 3660);
DISPLAY 0.617021 (410 3660);
PAINT ORANGE (410 3660);
FORCEPROP 2 LASTPIN (400 3400) $PN 152
J 0
(410 3410);
DISPLAY 0.617021 (410 3410);
PAINT ORANGE (410 3410);
FORCEPROP 2 LASTPIN (400 3450) $PN 153
J 0
(410 3460);
DISPLAY 0.617021 (410 3460);
PAINT ORANGE (410 3460);
FORCEPROP 2 LASTPIN (400 3500) $PN 163
J 0
(410 3510);
DISPLAY 0.617021 (410 3510);
PAINT ORANGE (410 3510);
FORCEPROP 2 LASTPIN (400 3550) $PN 164
J 0
(410 3560);
DISPLAY 0.617021 (410 3560);
PAINT ORANGE (410 3560);
FORCEPROP 2 LASTPIN (400 3600) $PN 174
J 0
(410 3610);
DISPLAY 0.617021 (410 3610);
PAINT ORANGE (410 3610);
FORCEPROP 2 LASTPIN (400 3700) $PN 185
J 0
(410 3710);
DISPLAY 0.617021 (410 3710);
PAINT ORANGE (410 3710);
FORCEPROP 2 LASTPIN (400 3750) $PN 186
J 0
(410 3760);
DISPLAY 0.617021 (410 3760);
PAINT ORANGE (410 3760);
FORCEPROP 2 LASTPIN (400 3800) $PN 244
J 0
(410 3810);
DISPLAY 0.617021 (410 3810);
PAINT ORANGE (410 3810);
FORCEPROP 2 LASTPIN (400 3850) $PN 245
J 0
(410 3860);
DISPLAY 0.617021 (410 3860);
PAINT ORANGE (410 3860);
FORCEPROP 2 LASTPIN (400 3900) $PN 255
J 0
(410 3910);
DISPLAY 0.617021 (410 3910);
PAINT ORANGE (410 3910);
FORCEPROP 2 LASTPIN (400 4000) $PN 266
J 0
(410 4010);
DISPLAY 0.617021 (410 4010);
PAINT ORANGE (410 4010);
FORCEPROP 2 LASTPIN (400 4050) $PN 267
J 0
(410 4060);
DISPLAY 0.617021 (410 4060);
PAINT ORANGE (410 4060);
FORCEPROP 2 LASTPIN (400 4150) $PN 278
J 0
(410 4160);
DISPLAY 0.617021 (410 4160);
PAINT ORANGE (410 4160);
FORCEPROP 2 LASTPIN (400 4200) $PN 196
J 0
(410 4210);
DISPLAY 0.617021 (410 4210);
PAINT ORANGE (410 4210);
FORCEPROP 2 LASTPIN (400 4250) $PN 197
J 0
(410 4260);
DISPLAY 0.617021 (410 4260);
PAINT ORANGE (410 4260);
FORCEPROP 2 LASTPIN (400 4300) $PN 8
J 0
(410 4310);
DISPLAY 0.617021 (410 4310);
PAINT ORANGE (410 4310);
FORCEPROP 2 LASTPIN (400 4350) $PN 7
J 0
(410 4360);
DISPLAY 0.617021 (410 4360);
PAINT ORANGE (410 4360);
FORCEPROP 2 LASTPIN (400 4400) $PN 19
J 0
(410 4410);
DISPLAY 0.617021 (410 4410);
PAINT ORANGE (410 4410);
FORCEPROP 2 LASTPIN (400 4450) $PN 18
J 0
(410 4460);
DISPLAY 0.617021 (410 4460);
PAINT ORANGE (410 4460);
FORCEPROP 2 LASTPIN (400 4500) $PN 30
J 0
(410 4510);
DISPLAY 0.617021 (410 4510);
PAINT ORANGE (410 4510);
FORCEPROP 2 LASTPIN (400 4550) $PN 29
J 0
(410 4560);
DISPLAY 0.617021 (410 4560);
PAINT ORANGE (410 4560);
FORCEPROP 2 LASTPIN (400 4600) $PN 41
J 0
(410 4610);
DISPLAY 0.617021 (410 4610);
PAINT ORANGE (410 4610);
FORCEPROP 2 LASTPIN (400 4650) $PN 40
J 0
(410 4660);
DISPLAY 0.617021 (410 4660);
PAINT ORANGE (410 4660);
FORCEPROP 2 LASTPIN (400 4700) $PN 100
J 0
(410 4710);
DISPLAY 0.617021 (410 4710);
PAINT ORANGE (410 4710);
FORCEPROP 2 LASTPIN (400 4750) $PN 99
J 0
(410 4760);
DISPLAY 0.617021 (410 4760);
PAINT ORANGE (410 4760);
FORCEPROP 2 LASTPIN (400 4800) $PN 111
J 0
(410 4810);
DISPLAY 0.617021 (410 4810);
PAINT ORANGE (410 4810);
FORCEPROP 2 LASTPIN (400 4850) $PN 110
J 0
(410 4860);
DISPLAY 0.617021 (410 4860);
PAINT ORANGE (410 4860);
FORCEPROP 2 LASTPIN (400 4900) $PN 122
J 0
(410 4910);
DISPLAY 0.617021 (410 4910);
PAINT ORANGE (410 4910);
FORCEPROP 2 LASTPIN (400 4950) $PN 121
J 0
(410 4960);
DISPLAY 0.617021 (410 4960);
PAINT ORANGE (410 4960);
FORCEPROP 2 LASTPIN (400 5000) $PN 133
J 0
(410 5010);
DISPLAY 0.617021 (410 5010);
PAINT ORANGE (410 5010);
FORCEPROP 2 LASTPIN (400 5050) $PN 132
J 0
(410 5060);
DISPLAY 0.617021 (410 5060);
PAINT ORANGE (410 5060);
FORCEPROP 2 LASTPIN (400 5100) $PN 52
J 0
(410 5110);
DISPLAY 0.617021 (410 5110);
PAINT ORANGE (410 5110);
FORCEPROP 2 LASTPIN (400 5150) $PN 51
J 0
(410 5160);
DISPLAY 0.617021 (410 5160);
PAINT ORANGE (410 5160);
FORCEPROP 1 LAST MATERIAL SCONN
J 0
(-450 5350);
DISPLAY 0.617021 (-450 5350);
PAINT SKYBLUE (-450 5350);
FORCEPROP 1 LAST PART_NUMBER H44441-003
J 0
(-450 3200);
DISPLAY 0.617021 (-450 3200);
PAINT BLUE (-450 3200);
FORCEPROP 1 LAST LOCATION J9U2
J 0
(-450 5400);
DISPLAY 0.617021 (-450 5400);
PAINT AQUA (-450 5400);
FORCEPROP 2 LAST ROOM DDR4_CH_J
J 0
(-50 4300);
PAINT ORANGE (-50 4300);
DISPLAY INVISIBLE (-50 4300);
FORCEPROP 1 LAST PATH I64
J 0
(-50 5350);
PAINT GREEN (-50 5350);
DISPLAY INVISIBLE (-50 5350);
FORCEPROP 2 LAST CDS_LOCATION J9U2
J 0
(-450 5400);
DISPLAY 0.617021 (-450 5400);
PAINT AQUA (-450 5400);
DISPLAY INVISIBLE (-450 5400);
FORCEPROP 2 LAST SEC 2
J 0
(-450 5450);
DISPLAY 0.680851 (-450 5450);
PAINT MONO (-450 5450);
DISPLAY INVISIBLE (-450 5450);
FORCEPROP 2 LAST SEC_TYPE PIP
J 0
(-450 5450);
DISPLAY 1.021277 (-450 5450);
PAINT ORANGE (-450 5450);
DISPLAY INVISIBLE (-450 5450);
FORCEPROP 2 LAST CDS_LIB mstr_sconn
J 0
(-50 4300);
PAINT ORANGE (-50 4300);
DISPLAY INVISIBLE (-50 4300);
FORCEPROP 2 LAST BOM_COST MEM
J 0
(-50 4300);
PAINT ORANGE (-50 4300);
DISPLAY INVISIBLE (-50 4300);
FORCEPROP 1 LAST PACK_TYPE PIP
J 0
(-450 5450);
PAINT SKYBLUE (-450 5450);
DISPLAY INVISIBLE (-450 5450);
FORCEADD TAP..6
R 2
(-1750 3800);
FORCEPROP 3 LASTPIN (-1800 3800) SIG_NAME M_J_DQ<43>
J 0
(-1790 3810);
DISPLAY 0.659574 (-1790 3810);
PAINT MONO (-1790 3810);
DISPLAY INVISIBLE (-1790 3810);
FORCEPROP 1 LASTPIN (-1800 3800) BN 43
J 2
(-1750 3810);
DISPLAY 0.617021 (-1750 3810);
PAINT PINK (-1750 3810);
FORCEPROP 1 LAST PATH I65
J 2
(-1750 3800);
DISPLAY 0.936170 (-1750 3800);
PAINT GREEN (-1750 3800);
DISPLAY INVISIBLE (-1750 3800);
FORCEPROP 1 LAST HDL_TAP TRUE
J 2
(-2075 3675);
DISPLAY 1.234043 (-2075 3675);
PAINT GREEN (-2075 3675);
DISPLAY INVISIBLE (-2075 3675);
FORCEPROP 1 LAST BODY_TYPE PLUMBING
J 2
(-1750 3750);
DISPLAY 1.234043 (-1750 3750);
PAINT GREEN (-1750 3750);
DISPLAY INVISIBLE (-1750 3750);
FORCEPROP 2 LAST CDS_LIB mstr_standard
J 2
(-1750 3800);
DISPLAY 0.787234 (-1750 3800);
PAINT MONO (-1750 3800);
DISPLAY INVISIBLE (-1750 3800);
FORCEADD TAP..6
R 2
(-1750 3750);
FORCEPROP 3 LASTPIN (-1800 3750) SIG_NAME M_J_DQ<42>
J 0
(-1790 3760);
DISPLAY 0.659574 (-1790 3760);
PAINT MONO (-1790 3760);
DISPLAY INVISIBLE (-1790 3760);
FORCEPROP 1 LASTPIN (-1800 3750) BN 42
J 2
(-1750 3760);
DISPLAY 0.617021 (-1750 3760);
PAINT PINK (-1750 3760);
FORCEPROP 1 LAST PATH I66
J 2
(-1750 3750);
DISPLAY 0.936170 (-1750 3750);
PAINT GREEN (-1750 3750);
DISPLAY INVISIBLE (-1750 3750);
FORCEPROP 1 LAST HDL_TAP TRUE
J 2
(-2075 3625);
DISPLAY 1.234043 (-2075 3625);
PAINT GREEN (-2075 3625);
DISPLAY INVISIBLE (-2075 3625);
FORCEPROP 1 LAST BODY_TYPE PLUMBING
J 2
(-1750 3700);
DISPLAY 1.234043 (-1750 3700);
PAINT GREEN (-1750 3700);
DISPLAY INVISIBLE (-1750 3700);
FORCEPROP 2 LAST CDS_LIB mstr_standard
J 2
(-1750 3750);
DISPLAY 0.787234 (-1750 3750);
PAINT MONO (-1750 3750);
DISPLAY INVISIBLE (-1750 3750);
FORCEADD TAP..6
R 2
(-1750 3700);
FORCEPROP 3 LASTPIN (-1800 3700) SIG_NAME M_J_DQ<41>
J 0
(-1790 3710);
DISPLAY 0.659574 (-1790 3710);
PAINT MONO (-1790 3710);
DISPLAY INVISIBLE (-1790 3710);
FORCEPROP 1 LASTPIN (-1800 3700) BN 41
J 2
(-1750 3710);
DISPLAY 0.617021 (-1750 3710);
PAINT PINK (-1750 3710);
FORCEPROP 1 LAST PATH I67
J 2
(-1750 3700);
DISPLAY 0.936170 (-1750 3700);
PAINT GREEN (-1750 3700);
DISPLAY INVISIBLE (-1750 3700);
FORCEPROP 1 LAST HDL_TAP TRUE
J 2
(-2075 3575);
DISPLAY 1.234043 (-2075 3575);
PAINT GREEN (-2075 3575);
DISPLAY INVISIBLE (-2075 3575);
FORCEPROP 1 LAST BODY_TYPE PLUMBING
J 2
(-1750 3650);
DISPLAY 1.234043 (-1750 3650);
PAINT GREEN (-1750 3650);
DISPLAY INVISIBLE (-1750 3650);
FORCEPROP 2 LAST CDS_LIB mstr_standard
J 2
(-1750 3700);
DISPLAY 0.787234 (-1750 3700);
PAINT MONO (-1750 3700);
DISPLAY INVISIBLE (-1750 3700);
FORCEADD TAP..6
R 2
(-1750 3850);
FORCEPROP 3 LASTPIN (-1800 3850) SIG_NAME M_J_DQ<44>
J 0
(-1790 3860);
DISPLAY 0.659574 (-1790 3860);
PAINT MONO (-1790 3860);
DISPLAY INVISIBLE (-1790 3860);
FORCEPROP 1 LASTPIN (-1800 3850) BN 44
J 2
(-1750 3860);
DISPLAY 0.617021 (-1750 3860);
PAINT PINK (-1750 3860);
FORCEPROP 1 LAST PATH I68
J 2
(-1750 3850);
DISPLAY 0.936170 (-1750 3850);
PAINT GREEN (-1750 3850);
DISPLAY INVISIBLE (-1750 3850);
FORCEPROP 1 LAST HDL_TAP TRUE
J 2
(-2075 3725);
DISPLAY 1.234043 (-2075 3725);
PAINT GREEN (-2075 3725);
DISPLAY INVISIBLE (-2075 3725);
FORCEPROP 1 LAST BODY_TYPE PLUMBING
J 2
(-1750 3800);
DISPLAY 1.234043 (-1750 3800);
PAINT GREEN (-1750 3800);
DISPLAY INVISIBLE (-1750 3800);
FORCEPROP 2 LAST CDS_LIB mstr_standard
J 2
(-1750 3850);
DISPLAY 0.787234 (-1750 3850);
PAINT MONO (-1750 3850);
DISPLAY INVISIBLE (-1750 3850);
FORCEADD TAP..6
R 2
(-1750 3900);
FORCEPROP 3 LASTPIN (-1800 3900) SIG_NAME M_J_DQ<45>
J 0
(-1790 3910);
DISPLAY 0.659574 (-1790 3910);
PAINT MONO (-1790 3910);
DISPLAY INVISIBLE (-1790 3910);
FORCEPROP 1 LASTPIN (-1800 3900) BN 45
J 2
(-1750 3910);
DISPLAY 0.617021 (-1750 3910);
PAINT PINK (-1750 3910);
FORCEPROP 1 LAST PATH I69
J 2
(-1750 3900);
DISPLAY 0.936170 (-1750 3900);
PAINT GREEN (-1750 3900);
DISPLAY INVISIBLE (-1750 3900);
FORCEPROP 1 LAST HDL_TAP TRUE
J 2
(-2075 3775);
DISPLAY 1.234043 (-2075 3775);
PAINT GREEN (-2075 3775);
DISPLAY INVISIBLE (-2075 3775);
FORCEPROP 1 LAST BODY_TYPE PLUMBING
J 2
(-1750 3850);
DISPLAY 1.234043 (-1750 3850);
PAINT GREEN (-1750 3850);
DISPLAY INVISIBLE (-1750 3850);
FORCEPROP 2 LAST CDS_LIB mstr_standard
J 2
(-1750 3900);
DISPLAY 0.787234 (-1750 3900);
PAINT MONO (-1750 3900);
DISPLAY INVISIBLE (-1750 3900);
FORCEADD TAP..6
R 2
(850 4700);
FORCEPROP 3 LASTPIN (800 4700) SIG_NAME M_J_DQS_DN<13>
J 0
(810 4710);
DISPLAY 0.659574 (810 4710);
PAINT MONO (810 4710);
DISPLAY INVISIBLE (810 4710);
FORCEPROP 1 LASTPIN (800 4700) BN 13
J 2
(850 4710);
DISPLAY 0.617021 (850 4710);
PAINT PINK (850 4710);
FORCEPROP 1 LAST PATH I7
J 2
(850 4700);
DISPLAY 0.936170 (850 4700);
PAINT GREEN (850 4700);
DISPLAY INVISIBLE (850 4700);
FORCEPROP 1 LAST HDL_TAP TRUE
J 2
(525 4575);
DISPLAY 1.234043 (525 4575);
PAINT GREEN (525 4575);
DISPLAY INVISIBLE (525 4575);
FORCEPROP 1 LAST BODY_TYPE PLUMBING
J 2
(850 4650);
DISPLAY 1.234043 (850 4650);
PAINT GREEN (850 4650);
DISPLAY INVISIBLE (850 4650);
FORCEPROP 2 LAST CDS_LIB mstr_standard
J 0
(850 4700);
DISPLAY 0.787234 (850 4700);
PAINT MONO (850 4700);
DISPLAY INVISIBLE (850 4700);
FORCEADD TAP..6
R 2
(-1750 3550);
FORCEPROP 3 LASTPIN (-1800 3550) SIG_NAME M_J_DQ<38>
J 0
(-1790 3560);
DISPLAY 0.659574 (-1790 3560);
PAINT MONO (-1790 3560);
DISPLAY INVISIBLE (-1790 3560);
FORCEPROP 1 LASTPIN (-1800 3550) BN 38
J 2
(-1750 3560);
DISPLAY 0.617021 (-1750 3560);
PAINT PINK (-1750 3560);
FORCEPROP 1 LAST PATH I70
J 2
(-1750 3550);
DISPLAY 0.936170 (-1750 3550);
PAINT GREEN (-1750 3550);
DISPLAY INVISIBLE (-1750 3550);
FORCEPROP 1 LAST HDL_TAP TRUE
J 2
(-2075 3425);
DISPLAY 1.234043 (-2075 3425);
PAINT GREEN (-2075 3425);
DISPLAY INVISIBLE (-2075 3425);
FORCEPROP 1 LAST BODY_TYPE PLUMBING
J 2
(-1750 3500);
DISPLAY 1.234043 (-1750 3500);
PAINT GREEN (-1750 3500);
DISPLAY INVISIBLE (-1750 3500);
FORCEPROP 2 LAST CDS_LIB mstr_standard
J 2
(-1750 3550);
DISPLAY 0.787234 (-1750 3550);
PAINT MONO (-1750 3550);
DISPLAY INVISIBLE (-1750 3550);
FORCEADD TAP..6
R 2
(-1750 3500);
FORCEPROP 3 LASTPIN (-1800 3500) SIG_NAME M_J_DQ<37>
J 0
(-1790 3510);
DISPLAY 0.659574 (-1790 3510);
PAINT MONO (-1790 3510);
DISPLAY INVISIBLE (-1790 3510);
FORCEPROP 1 LASTPIN (-1800 3500) BN 37
J 2
(-1750 3510);
DISPLAY 0.617021 (-1750 3510);
PAINT PINK (-1750 3510);
FORCEPROP 1 LAST PATH I71
J 2
(-1750 3500);
DISPLAY 0.936170 (-1750 3500);
PAINT GREEN (-1750 3500);
DISPLAY INVISIBLE (-1750 3500);
FORCEPROP 1 LAST HDL_TAP TRUE
J 2
(-2075 3375);
DISPLAY 1.234043 (-2075 3375);
PAINT GREEN (-2075 3375);
DISPLAY INVISIBLE (-2075 3375);
FORCEPROP 1 LAST BODY_TYPE PLUMBING
J 2
(-1750 3450);
DISPLAY 1.234043 (-1750 3450);
PAINT GREEN (-1750 3450);
DISPLAY INVISIBLE (-1750 3450);
FORCEPROP 2 LAST CDS_LIB mstr_standard
J 2
(-1750 3500);
DISPLAY 0.787234 (-1750 3500);
PAINT MONO (-1750 3500);
DISPLAY INVISIBLE (-1750 3500);
FORCEADD TAP..6
R 2
(-1750 3450);
FORCEPROP 3 LASTPIN (-1800 3450) SIG_NAME M_J_DQ<36>
J 0
(-1790 3460);
DISPLAY 0.659574 (-1790 3460);
PAINT MONO (-1790 3460);
DISPLAY INVISIBLE (-1790 3460);
FORCEPROP 1 LASTPIN (-1800 3450) BN 36
J 2
(-1750 3460);
DISPLAY 0.617021 (-1750 3460);
PAINT PINK (-1750 3460);
FORCEPROP 1 LAST PATH I72
J 2
(-1750 3450);
DISPLAY 0.936170 (-1750 3450);
PAINT GREEN (-1750 3450);
DISPLAY INVISIBLE (-1750 3450);
FORCEPROP 1 LAST HDL_TAP TRUE
J 2
(-2075 3325);
DISPLAY 1.234043 (-2075 3325);
PAINT GREEN (-2075 3325);
DISPLAY INVISIBLE (-2075 3325);
FORCEPROP 1 LAST BODY_TYPE PLUMBING
J 2
(-1750 3400);
DISPLAY 1.234043 (-1750 3400);
PAINT GREEN (-1750 3400);
DISPLAY INVISIBLE (-1750 3400);
FORCEPROP 2 LAST CDS_LIB mstr_standard
J 2
(-1750 3450);
DISPLAY 0.787234 (-1750 3450);
PAINT MONO (-1750 3450);
DISPLAY INVISIBLE (-1750 3450);
FORCEADD TAP..6
R 2
(-1750 3650);
FORCEPROP 3 LASTPIN (-1800 3650) SIG_NAME M_J_DQ<40>
J 0
(-1790 3660);
DISPLAY 0.659574 (-1790 3660);
PAINT MONO (-1790 3660);
DISPLAY INVISIBLE (-1790 3660);
FORCEPROP 1 LASTPIN (-1800 3650) BN 40
J 2
(-1750 3660);
DISPLAY 0.617021 (-1750 3660);
PAINT PINK (-1750 3660);
FORCEPROP 1 LAST PATH I73
J 2
(-1750 3650);
DISPLAY 0.936170 (-1750 3650);
PAINT GREEN (-1750 3650);
DISPLAY INVISIBLE (-1750 3650);
FORCEPROP 1 LAST HDL_TAP TRUE
J 2
(-2075 3525);
DISPLAY 1.234043 (-2075 3525);
PAINT GREEN (-2075 3525);
DISPLAY INVISIBLE (-2075 3525);
FORCEPROP 1 LAST BODY_TYPE PLUMBING
J 2
(-1750 3600);
DISPLAY 1.234043 (-1750 3600);
PAINT GREEN (-1750 3600);
DISPLAY INVISIBLE (-1750 3600);
FORCEPROP 2 LAST CDS_LIB mstr_standard
J 2
(-1750 3650);
DISPLAY 0.787234 (-1750 3650);
PAINT MONO (-1750 3650);
DISPLAY INVISIBLE (-1750 3650);
FORCEADD TAP..6
R 2
(-1750 3600);
FORCEPROP 3 LASTPIN (-1800 3600) SIG_NAME M_J_DQ<39>
J 0
(-1790 3610);
DISPLAY 0.659574 (-1790 3610);
PAINT MONO (-1790 3610);
DISPLAY INVISIBLE (-1790 3610);
FORCEPROP 1 LASTPIN (-1800 3600) BN 39
J 2
(-1750 3610);
DISPLAY 0.617021 (-1750 3610);
PAINT PINK (-1750 3610);
FORCEPROP 1 LAST PATH I74
J 2
(-1750 3600);
DISPLAY 0.936170 (-1750 3600);
PAINT GREEN (-1750 3600);
DISPLAY INVISIBLE (-1750 3600);
FORCEPROP 1 LAST HDL_TAP TRUE
J 2
(-2075 3475);
DISPLAY 1.234043 (-2075 3475);
PAINT GREEN (-2075 3475);
DISPLAY INVISIBLE (-2075 3475);
FORCEPROP 1 LAST BODY_TYPE PLUMBING
J 2
(-1750 3550);
DISPLAY 1.234043 (-1750 3550);
PAINT GREEN (-1750 3550);
DISPLAY INVISIBLE (-1750 3550);
FORCEPROP 2 LAST CDS_LIB mstr_standard
J 2
(-1750 3600);
DISPLAY 0.787234 (-1750 3600);
PAINT MONO (-1750 3600);
DISPLAY INVISIBLE (-1750 3600);
FORCEADD TAP..6
R 2
(-1750 3300);
FORCEPROP 3 LASTPIN (-1800 3300) SIG_NAME M_J_DQ<33>
J 0
(-1790 3310);
DISPLAY 0.659574 (-1790 3310);
PAINT MONO (-1790 3310);
DISPLAY INVISIBLE (-1790 3310);
FORCEPROP 1 LASTPIN (-1800 3300) BN 33
J 2
(-1750 3310);
DISPLAY 0.617021 (-1750 3310);
PAINT PINK (-1750 3310);
FORCEPROP 1 LAST PATH I75
J 2
(-1750 3300);
DISPLAY 0.936170 (-1750 3300);
PAINT GREEN (-1750 3300);
DISPLAY INVISIBLE (-1750 3300);
FORCEPROP 1 LAST HDL_TAP TRUE
J 2
(-2075 3175);
DISPLAY 1.234043 (-2075 3175);
PAINT GREEN (-2075 3175);
DISPLAY INVISIBLE (-2075 3175);
FORCEPROP 1 LAST BODY_TYPE PLUMBING
J 2
(-1750 3250);
DISPLAY 1.234043 (-1750 3250);
PAINT GREEN (-1750 3250);
DISPLAY INVISIBLE (-1750 3250);
FORCEPROP 2 LAST CDS_LIB mstr_standard
J 2
(-1750 3300);
DISPLAY 0.787234 (-1750 3300);
PAINT MONO (-1750 3300);
DISPLAY INVISIBLE (-1750 3300);
FORCEADD TAP..6
R 2
(-1750 3250);
FORCEPROP 3 LASTPIN (-1800 3250) SIG_NAME M_J_DQ<32>
J 0
(-1790 3260);
DISPLAY 0.659574 (-1790 3260);
PAINT MONO (-1790 3260);
DISPLAY INVISIBLE (-1790 3260);
FORCEPROP 1 LASTPIN (-1800 3250) BN 32
J 2
(-1750 3260);
DISPLAY 0.617021 (-1750 3260);
PAINT PINK (-1750 3260);
FORCEPROP 1 LAST PATH I76
J 2
(-1750 3250);
DISPLAY 0.936170 (-1750 3250);
PAINT GREEN (-1750 3250);
DISPLAY INVISIBLE (-1750 3250);
FORCEPROP 1 LAST HDL_TAP TRUE
J 2
(-2075 3125);
DISPLAY 1.234043 (-2075 3125);
PAINT GREEN (-2075 3125);
DISPLAY INVISIBLE (-2075 3125);
FORCEPROP 1 LAST BODY_TYPE PLUMBING
J 2
(-1750 3200);
DISPLAY 1.234043 (-1750 3200);
PAINT GREEN (-1750 3200);
DISPLAY INVISIBLE (-1750 3200);
FORCEPROP 2 LAST CDS_LIB mstr_standard
J 2
(-1750 3250);
DISPLAY 0.787234 (-1750 3250);
PAINT MONO (-1750 3250);
DISPLAY INVISIBLE (-1750 3250);
FORCEADD TAP..6
R 2
(-1750 3200);
FORCEPROP 3 LASTPIN (-1800 3200) SIG_NAME M_J_DQ<31>
J 0
(-1790 3210);
DISPLAY 0.659574 (-1790 3210);
PAINT MONO (-1790 3210);
DISPLAY INVISIBLE (-1790 3210);
FORCEPROP 1 LASTPIN (-1800 3200) BN 31
J 2
(-1750 3210);
DISPLAY 0.617021 (-1750 3210);
PAINT PINK (-1750 3210);
FORCEPROP 1 LAST PATH I77
J 2
(-1750 3200);
DISPLAY 0.936170 (-1750 3200);
PAINT GREEN (-1750 3200);
DISPLAY INVISIBLE (-1750 3200);
FORCEPROP 1 LAST HDL_TAP TRUE
J 2
(-2075 3075);
DISPLAY 1.234043 (-2075 3075);
PAINT GREEN (-2075 3075);
DISPLAY INVISIBLE (-2075 3075);
FORCEPROP 1 LAST BODY_TYPE PLUMBING
J 2
(-1750 3150);
DISPLAY 1.234043 (-1750 3150);
PAINT GREEN (-1750 3150);
DISPLAY INVISIBLE (-1750 3150);
FORCEPROP 2 LAST CDS_LIB mstr_standard
J 2
(-1750 3200);
DISPLAY 0.787234 (-1750 3200);
PAINT MONO (-1750 3200);
DISPLAY INVISIBLE (-1750 3200);
FORCEADD TAP..6
R 2
(-1750 3400);
FORCEPROP 3 LASTPIN (-1800 3400) SIG_NAME M_J_DQ<35>
J 0
(-1790 3410);
DISPLAY 0.659574 (-1790 3410);
PAINT MONO (-1790 3410);
DISPLAY INVISIBLE (-1790 3410);
FORCEPROP 1 LASTPIN (-1800 3400) BN 35
J 2
(-1750 3410);
DISPLAY 0.617021 (-1750 3410);
PAINT PINK (-1750 3410);
FORCEPROP 1 LAST PATH I78
J 2
(-1750 3400);
DISPLAY 0.936170 (-1750 3400);
PAINT GREEN (-1750 3400);
DISPLAY INVISIBLE (-1750 3400);
FORCEPROP 1 LAST HDL_TAP TRUE
J 2
(-2075 3275);
DISPLAY 1.234043 (-2075 3275);
PAINT GREEN (-2075 3275);
DISPLAY INVISIBLE (-2075 3275);
FORCEPROP 1 LAST BODY_TYPE PLUMBING
J 2
(-1750 3350);
DISPLAY 1.234043 (-1750 3350);
PAINT GREEN (-1750 3350);
DISPLAY INVISIBLE (-1750 3350);
FORCEPROP 2 LAST CDS_LIB mstr_standard
J 2
(-1750 3400);
DISPLAY 0.787234 (-1750 3400);
PAINT MONO (-1750 3400);
DISPLAY INVISIBLE (-1750 3400);
FORCEADD TAP..6
R 2
(-1750 3350);
FORCEPROP 3 LASTPIN (-1800 3350) SIG_NAME M_J_DQ<34>
J 0
(-1790 3360);
DISPLAY 0.659574 (-1790 3360);
PAINT MONO (-1790 3360);
DISPLAY INVISIBLE (-1790 3360);
FORCEPROP 1 LASTPIN (-1800 3350) BN 34
J 2
(-1750 3360);
DISPLAY 0.617021 (-1750 3360);
PAINT PINK (-1750 3360);
FORCEPROP 1 LAST PATH I79
J 2
(-1750 3350);
DISPLAY 0.936170 (-1750 3350);
PAINT GREEN (-1750 3350);
DISPLAY INVISIBLE (-1750 3350);
FORCEPROP 1 LAST HDL_TAP TRUE
J 2
(-2075 3225);
DISPLAY 1.234043 (-2075 3225);
PAINT GREEN (-2075 3225);
DISPLAY INVISIBLE (-2075 3225);
FORCEPROP 1 LAST BODY_TYPE PLUMBING
J 2
(-1750 3300);
DISPLAY 1.234043 (-1750 3300);
PAINT GREEN (-1750 3300);
DISPLAY INVISIBLE (-1750 3300);
FORCEPROP 2 LAST CDS_LIB mstr_standard
J 2
(-1750 3350);
DISPLAY 0.787234 (-1750 3350);
PAINT MONO (-1750 3350);
DISPLAY INVISIBLE (-1750 3350);
FORCEADD TAP..6
R 2
(650 5050);
FORCEPROP 3 LASTPIN (600 5050) SIG_NAME M_J_DQS_DP<16>
J 0
(610 5060);
DISPLAY 0.659574 (610 5060);
PAINT MONO (610 5060);
DISPLAY INVISIBLE (610 5060);
FORCEPROP 1 LASTPIN (600 5050) BN 16
J 2
(650 5060);
DISPLAY 0.617021 (650 5060);
PAINT PINK (650 5060);
FORCEPROP 1 LAST PATH I8
J 2
(650 5050);
DISPLAY 0.936170 (650 5050);
PAINT GREEN (650 5050);
DISPLAY INVISIBLE (650 5050);
FORCEPROP 1 LAST HDL_TAP TRUE
J 2
(325 4925);
DISPLAY 1.234043 (325 4925);
PAINT GREEN (325 4925);
DISPLAY INVISIBLE (325 4925);
FORCEPROP 1 LAST BODY_TYPE PLUMBING
J 2
(650 5000);
DISPLAY 1.234043 (650 5000);
PAINT GREEN (650 5000);
DISPLAY INVISIBLE (650 5000);
FORCEPROP 2 LAST CDS_LIB mstr_standard
J 0
(650 5050);
DISPLAY 0.787234 (650 5050);
PAINT MONO (650 5050);
DISPLAY INVISIBLE (650 5050);
FORCEADD TAP..6
R 2
(-1750 3000);
FORCEPROP 3 LASTPIN (-1800 3000) SIG_NAME M_J_DQ<27>
J 0
(-1790 3010);
DISPLAY 0.659574 (-1790 3010);
PAINT MONO (-1790 3010);
DISPLAY INVISIBLE (-1790 3010);
FORCEPROP 1 LASTPIN (-1800 3000) BN 27
J 2
(-1750 3010);
DISPLAY 0.617021 (-1750 3010);
PAINT PINK (-1750 3010);
FORCEPROP 1 LAST PATH I80
J 2
(-1750 3000);
DISPLAY 0.936170 (-1750 3000);
PAINT GREEN (-1750 3000);
DISPLAY INVISIBLE (-1750 3000);
FORCEPROP 1 LAST HDL_TAP TRUE
J 2
(-2075 2875);
DISPLAY 1.234043 (-2075 2875);
PAINT GREEN (-2075 2875);
DISPLAY INVISIBLE (-2075 2875);
FORCEPROP 1 LAST BODY_TYPE PLUMBING
J 2
(-1750 2950);
DISPLAY 1.234043 (-1750 2950);
PAINT GREEN (-1750 2950);
DISPLAY INVISIBLE (-1750 2950);
FORCEPROP 2 LAST CDS_LIB mstr_standard
J 2
(-1750 3000);
DISPLAY 0.787234 (-1750 3000);
PAINT MONO (-1750 3000);
DISPLAY INVISIBLE (-1750 3000);
FORCEADD TAP..6
R 2
(-1750 3050);
FORCEPROP 3 LASTPIN (-1800 3050) SIG_NAME M_J_DQ<28>
J 0
(-1790 3060);
DISPLAY 0.659574 (-1790 3060);
PAINT MONO (-1790 3060);
DISPLAY INVISIBLE (-1790 3060);
FORCEPROP 1 LASTPIN (-1800 3050) BN 28
J 2
(-1750 3060);
DISPLAY 0.617021 (-1750 3060);
PAINT PINK (-1750 3060);
FORCEPROP 1 LAST PATH I81
J 2
(-1750 3050);
DISPLAY 0.936170 (-1750 3050);
PAINT GREEN (-1750 3050);
DISPLAY INVISIBLE (-1750 3050);
FORCEPROP 1 LAST HDL_TAP TRUE
J 2
(-2075 2925);
DISPLAY 1.234043 (-2075 2925);
PAINT GREEN (-2075 2925);
DISPLAY INVISIBLE (-2075 2925);
FORCEPROP 1 LAST BODY_TYPE PLUMBING
J 2
(-1750 3000);
DISPLAY 1.234043 (-1750 3000);
PAINT GREEN (-1750 3000);
DISPLAY INVISIBLE (-1750 3000);
FORCEPROP 2 LAST CDS_LIB mstr_standard
J 2
(-1750 3050);
DISPLAY 0.787234 (-1750 3050);
PAINT MONO (-1750 3050);
DISPLAY INVISIBLE (-1750 3050);
FORCEADD TAP..6
R 2
(-1750 2950);
FORCEPROP 3 LASTPIN (-1800 2950) SIG_NAME M_J_DQ<26>
J 0
(-1790 2960);
DISPLAY 0.659574 (-1790 2960);
PAINT MONO (-1790 2960);
DISPLAY INVISIBLE (-1790 2960);
FORCEPROP 1 LASTPIN (-1800 2950) BN 26
J 2
(-1750 2960);
DISPLAY 0.617021 (-1750 2960);
PAINT PINK (-1750 2960);
FORCEPROP 1 LAST PATH I82
J 2
(-1750 2950);
DISPLAY 0.936170 (-1750 2950);
PAINT GREEN (-1750 2950);
DISPLAY INVISIBLE (-1750 2950);
FORCEPROP 1 LAST HDL_TAP TRUE
J 2
(-2075 2825);
DISPLAY 1.234043 (-2075 2825);
PAINT GREEN (-2075 2825);
DISPLAY INVISIBLE (-2075 2825);
FORCEPROP 1 LAST BODY_TYPE PLUMBING
J 2
(-1750 2900);
DISPLAY 1.234043 (-1750 2900);
PAINT GREEN (-1750 2900);
DISPLAY INVISIBLE (-1750 2900);
FORCEPROP 2 LAST CDS_LIB mstr_standard
J 2
(-1750 2950);
DISPLAY 0.787234 (-1750 2950);
PAINT MONO (-1750 2950);
DISPLAY INVISIBLE (-1750 2950);
FORCEADD TAP..6
R 2
(-1750 3100);
FORCEPROP 3 LASTPIN (-1800 3100) SIG_NAME M_J_DQ<29>
J 0
(-1790 3110);
DISPLAY 0.659574 (-1790 3110);
PAINT MONO (-1790 3110);
DISPLAY INVISIBLE (-1790 3110);
FORCEPROP 1 LASTPIN (-1800 3100) BN 29
J 2
(-1750 3110);
DISPLAY 0.617021 (-1750 3110);
PAINT PINK (-1750 3110);
FORCEPROP 1 LAST PATH I83
J 2
(-1750 3100);
DISPLAY 0.936170 (-1750 3100);
PAINT GREEN (-1750 3100);
DISPLAY INVISIBLE (-1750 3100);
FORCEPROP 1 LAST HDL_TAP TRUE
J 2
(-2075 2975);
DISPLAY 1.234043 (-2075 2975);
PAINT GREEN (-2075 2975);
DISPLAY INVISIBLE (-2075 2975);
FORCEPROP 1 LAST BODY_TYPE PLUMBING
J 2
(-1750 3050);
DISPLAY 1.234043 (-1750 3050);
PAINT GREEN (-1750 3050);
DISPLAY INVISIBLE (-1750 3050);
FORCEPROP 2 LAST CDS_LIB mstr_standard
J 2
(-1750 3100);
DISPLAY 0.787234 (-1750 3100);
PAINT MONO (-1750 3100);
DISPLAY INVISIBLE (-1750 3100);
FORCEADD TAP..6
R 2
(-1750 3150);
FORCEPROP 3 LASTPIN (-1800 3150) SIG_NAME M_J_DQ<30>
J 0
(-1790 3160);
DISPLAY 0.659574 (-1790 3160);
PAINT MONO (-1790 3160);
DISPLAY INVISIBLE (-1790 3160);
FORCEPROP 1 LASTPIN (-1800 3150) BN 30
J 2
(-1750 3160);
DISPLAY 0.617021 (-1750 3160);
PAINT PINK (-1750 3160);
FORCEPROP 1 LAST PATH I84
J 2
(-1750 3150);
DISPLAY 0.936170 (-1750 3150);
PAINT GREEN (-1750 3150);
DISPLAY INVISIBLE (-1750 3150);
FORCEPROP 1 LAST HDL_TAP TRUE
J 2
(-2075 3025);
DISPLAY 1.234043 (-2075 3025);
PAINT GREEN (-2075 3025);
DISPLAY INVISIBLE (-2075 3025);
FORCEPROP 1 LAST BODY_TYPE PLUMBING
J 2
(-1750 3100);
DISPLAY 1.234043 (-1750 3100);
PAINT GREEN (-1750 3100);
DISPLAY INVISIBLE (-1750 3100);
FORCEPROP 2 LAST CDS_LIB mstr_standard
J 2
(-1750 3150);
DISPLAY 0.787234 (-1750 3150);
PAINT MONO (-1750 3150);
DISPLAY INVISIBLE (-1750 3150);
FORCEADD TAP..6
R 2
(-1750 2750);
FORCEPROP 3 LASTPIN (-1800 2750) SIG_NAME M_J_DQ<22>
J 0
(-1790 2760);
DISPLAY 0.659574 (-1790 2760);
PAINT MONO (-1790 2760);
DISPLAY INVISIBLE (-1790 2760);
FORCEPROP 1 LASTPIN (-1800 2750) BN 22
J 2
(-1750 2760);
DISPLAY 0.617021 (-1750 2760);
PAINT PINK (-1750 2760);
FORCEPROP 1 LAST PATH I85
J 2
(-1750 2750);
DISPLAY 0.936170 (-1750 2750);
PAINT GREEN (-1750 2750);
DISPLAY INVISIBLE (-1750 2750);
FORCEPROP 1 LAST HDL_TAP TRUE
J 2
(-2075 2625);
DISPLAY 1.234043 (-2075 2625);
PAINT GREEN (-2075 2625);
DISPLAY INVISIBLE (-2075 2625);
FORCEPROP 1 LAST BODY_TYPE PLUMBING
J 2
(-1750 2700);
DISPLAY 1.234043 (-1750 2700);
PAINT GREEN (-1750 2700);
DISPLAY INVISIBLE (-1750 2700);
FORCEPROP 2 LAST CDS_LIB mstr_standard
J 2
(-1750 2750);
DISPLAY 0.787234 (-1750 2750);
PAINT MONO (-1750 2750);
DISPLAY INVISIBLE (-1750 2750);
FORCEADD TAP..6
R 2
(-1750 2800);
FORCEPROP 3 LASTPIN (-1800 2800) SIG_NAME M_J_DQ<23>
J 0
(-1790 2810);
DISPLAY 0.659574 (-1790 2810);
PAINT MONO (-1790 2810);
DISPLAY INVISIBLE (-1790 2810);
FORCEPROP 1 LASTPIN (-1800 2800) BN 23
J 2
(-1750 2810);
DISPLAY 0.617021 (-1750 2810);
PAINT PINK (-1750 2810);
FORCEPROP 1 LAST PATH I86
J 2
(-1750 2800);
DISPLAY 0.936170 (-1750 2800);
PAINT GREEN (-1750 2800);
DISPLAY INVISIBLE (-1750 2800);
FORCEPROP 1 LAST HDL_TAP TRUE
J 2
(-2075 2675);
DISPLAY 1.234043 (-2075 2675);
PAINT GREEN (-2075 2675);
DISPLAY INVISIBLE (-2075 2675);
FORCEPROP 1 LAST BODY_TYPE PLUMBING
J 2
(-1750 2750);
DISPLAY 1.234043 (-1750 2750);
PAINT GREEN (-1750 2750);
DISPLAY INVISIBLE (-1750 2750);
FORCEPROP 2 LAST CDS_LIB mstr_standard
J 2
(-1750 2800);
DISPLAY 0.787234 (-1750 2800);
PAINT MONO (-1750 2800);
DISPLAY INVISIBLE (-1750 2800);
FORCEADD TAP..6
R 2
(-1750 2700);
FORCEPROP 3 LASTPIN (-1800 2700) SIG_NAME M_J_DQ<21>
J 0
(-1790 2710);
DISPLAY 0.659574 (-1790 2710);
PAINT MONO (-1790 2710);
DISPLAY INVISIBLE (-1790 2710);
FORCEPROP 1 LASTPIN (-1800 2700) BN 21
J 2
(-1750 2710);
DISPLAY 0.617021 (-1750 2710);
PAINT PINK (-1750 2710);
FORCEPROP 1 LAST PATH I87
J 2
(-1750 2700);
DISPLAY 0.936170 (-1750 2700);
PAINT GREEN (-1750 2700);
DISPLAY INVISIBLE (-1750 2700);
FORCEPROP 1 LAST HDL_TAP TRUE
J 2
(-2075 2575);
DISPLAY 1.234043 (-2075 2575);
PAINT GREEN (-2075 2575);
DISPLAY INVISIBLE (-2075 2575);
FORCEPROP 1 LAST BODY_TYPE PLUMBING
J 2
(-1750 2650);
DISPLAY 1.234043 (-1750 2650);
PAINT GREEN (-1750 2650);
DISPLAY INVISIBLE (-1750 2650);
FORCEPROP 2 LAST CDS_LIB mstr_standard
J 2
(-1750 2700);
DISPLAY 0.787234 (-1750 2700);
PAINT MONO (-1750 2700);
DISPLAY INVISIBLE (-1750 2700);
FORCEADD TAP..6
R 2
(-1750 2900);
FORCEPROP 3 LASTPIN (-1800 2900) SIG_NAME M_J_DQ<25>
J 0
(-1790 2910);
DISPLAY 0.659574 (-1790 2910);
PAINT MONO (-1790 2910);
DISPLAY INVISIBLE (-1790 2910);
FORCEPROP 1 LASTPIN (-1800 2900) BN 25
J 2
(-1750 2910);
DISPLAY 0.617021 (-1750 2910);
PAINT PINK (-1750 2910);
FORCEPROP 1 LAST PATH I88
J 2
(-1750 2900);
DISPLAY 0.936170 (-1750 2900);
PAINT GREEN (-1750 2900);
DISPLAY INVISIBLE (-1750 2900);
FORCEPROP 1 LAST HDL_TAP TRUE
J 2
(-2075 2775);
DISPLAY 1.234043 (-2075 2775);
PAINT GREEN (-2075 2775);
DISPLAY INVISIBLE (-2075 2775);
FORCEPROP 1 LAST BODY_TYPE PLUMBING
J 2
(-1750 2850);
DISPLAY 1.234043 (-1750 2850);
PAINT GREEN (-1750 2850);
DISPLAY INVISIBLE (-1750 2850);
FORCEPROP 2 LAST CDS_LIB mstr_standard
J 2
(-1750 2900);
DISPLAY 0.787234 (-1750 2900);
PAINT MONO (-1750 2900);
DISPLAY INVISIBLE (-1750 2900);
FORCEADD TAP..6
R 2
(-1750 2850);
FORCEPROP 3 LASTPIN (-1800 2850) SIG_NAME M_J_DQ<24>
J 0
(-1790 2860);
DISPLAY 0.659574 (-1790 2860);
PAINT MONO (-1790 2860);
DISPLAY INVISIBLE (-1790 2860);
FORCEPROP 1 LASTPIN (-1800 2850) BN 24
J 2
(-1750 2860);
DISPLAY 0.617021 (-1750 2860);
PAINT PINK (-1750 2860);
FORCEPROP 1 LAST PATH I89
J 2
(-1750 2850);
DISPLAY 0.936170 (-1750 2850);
PAINT GREEN (-1750 2850);
DISPLAY INVISIBLE (-1750 2850);
FORCEPROP 1 LAST HDL_TAP TRUE
J 2
(-2075 2725);
DISPLAY 1.234043 (-2075 2725);
PAINT GREEN (-2075 2725);
DISPLAY INVISIBLE (-2075 2725);
FORCEPROP 1 LAST BODY_TYPE PLUMBING
J 2
(-1750 2800);
DISPLAY 1.234043 (-1750 2800);
PAINT GREEN (-1750 2800);
DISPLAY INVISIBLE (-1750 2800);
FORCEPROP 2 LAST CDS_LIB mstr_standard
J 2
(-1750 2850);
DISPLAY 0.787234 (-1750 2850);
PAINT MONO (-1750 2850);
DISPLAY INVISIBLE (-1750 2850);
FORCEADD TAP..6
R 2
(650 5150);
FORCEPROP 3 LASTPIN (600 5150) SIG_NAME M_J_DQS_DP<17>
J 0
(610 5160);
DISPLAY 0.659574 (610 5160);
PAINT MONO (610 5160);
DISPLAY INVISIBLE (610 5160);
FORCEPROP 1 LASTPIN (600 5150) BN 17
J 2
(650 5160);
DISPLAY 0.617021 (650 5160);
PAINT PINK (650 5160);
FORCEPROP 1 LAST PATH I9
J 2
(650 5150);
DISPLAY 0.936170 (650 5150);
PAINT GREEN (650 5150);
DISPLAY INVISIBLE (650 5150);
FORCEPROP 1 LAST HDL_TAP TRUE
J 2
(325 5025);
DISPLAY 1.234043 (325 5025);
PAINT GREEN (325 5025);
DISPLAY INVISIBLE (325 5025);
FORCEPROP 1 LAST BODY_TYPE PLUMBING
J 2
(650 5100);
DISPLAY 1.234043 (650 5100);
PAINT GREEN (650 5100);
DISPLAY INVISIBLE (650 5100);
FORCEPROP 2 LAST CDS_LIB mstr_standard
J 2
(650 5150);
DISPLAY 0.787234 (650 5150);
PAINT MONO (650 5150);
DISPLAY INVISIBLE (650 5150);
FORCEADD TAP..6
R 2
(-1750 2450);
FORCEPROP 3 LASTPIN (-1800 2450) SIG_NAME M_J_DQ<16>
J 0
(-1790 2460);
DISPLAY 0.659574 (-1790 2460);
PAINT MONO (-1790 2460);
DISPLAY INVISIBLE (-1790 2460);
FORCEPROP 1 LASTPIN (-1800 2450) BN 16
J 2
(-1750 2460);
DISPLAY 0.617021 (-1750 2460);
PAINT PINK (-1750 2460);
FORCEPROP 1 LAST PATH I90
J 2
(-1750 2450);
DISPLAY 0.936170 (-1750 2450);
PAINT GREEN (-1750 2450);
DISPLAY INVISIBLE (-1750 2450);
FORCEPROP 1 LAST HDL_TAP TRUE
J 2
(-2075 2325);
DISPLAY 1.234043 (-2075 2325);
PAINT GREEN (-2075 2325);
DISPLAY INVISIBLE (-2075 2325);
FORCEPROP 1 LAST BODY_TYPE PLUMBING
J 2
(-1750 2400);
DISPLAY 1.234043 (-1750 2400);
PAINT GREEN (-1750 2400);
DISPLAY INVISIBLE (-1750 2400);
FORCEPROP 2 LAST CDS_LIB mstr_standard
J 2
(-1750 2450);
DISPLAY 0.787234 (-1750 2450);
PAINT MONO (-1750 2450);
DISPLAY INVISIBLE (-1750 2450);
FORCEADD TAP..6
R 2
(-1750 2500);
FORCEPROP 3 LASTPIN (-1800 2500) SIG_NAME M_J_DQ<17>
J 0
(-1790 2510);
DISPLAY 0.659574 (-1790 2510);
PAINT MONO (-1790 2510);
DISPLAY INVISIBLE (-1790 2510);
FORCEPROP 1 LASTPIN (-1800 2500) BN 17
J 2
(-1750 2510);
DISPLAY 0.617021 (-1750 2510);
PAINT PINK (-1750 2510);
FORCEPROP 1 LAST PATH I91
J 2
(-1750 2500);
DISPLAY 0.936170 (-1750 2500);
PAINT GREEN (-1750 2500);
DISPLAY INVISIBLE (-1750 2500);
FORCEPROP 1 LAST HDL_TAP TRUE
J 2
(-2075 2375);
DISPLAY 1.234043 (-2075 2375);
PAINT GREEN (-2075 2375);
DISPLAY INVISIBLE (-2075 2375);
FORCEPROP 1 LAST BODY_TYPE PLUMBING
J 2
(-1750 2450);
DISPLAY 1.234043 (-1750 2450);
PAINT GREEN (-1750 2450);
DISPLAY INVISIBLE (-1750 2450);
FORCEPROP 2 LAST CDS_LIB mstr_standard
J 2
(-1750 2500);
DISPLAY 0.787234 (-1750 2500);
PAINT MONO (-1750 2500);
DISPLAY INVISIBLE (-1750 2500);
FORCEADD TAP..6
R 2
(-1750 2550);
FORCEPROP 3 LASTPIN (-1800 2550) SIG_NAME M_J_DQ<18>
J 0
(-1790 2560);
DISPLAY 0.659574 (-1790 2560);
PAINT MONO (-1790 2560);
DISPLAY INVISIBLE (-1790 2560);
FORCEPROP 1 LASTPIN (-1800 2550) BN 18
J 2
(-1750 2560);
DISPLAY 0.617021 (-1750 2560);
PAINT PINK (-1750 2560);
FORCEPROP 1 LAST PATH I92
J 2
(-1750 2550);
DISPLAY 0.936170 (-1750 2550);
PAINT GREEN (-1750 2550);
DISPLAY INVISIBLE (-1750 2550);
FORCEPROP 1 LAST HDL_TAP TRUE
J 2
(-2075 2425);
DISPLAY 1.234043 (-2075 2425);
PAINT GREEN (-2075 2425);
DISPLAY INVISIBLE (-2075 2425);
FORCEPROP 1 LAST BODY_TYPE PLUMBING
J 2
(-1750 2500);
DISPLAY 1.234043 (-1750 2500);
PAINT GREEN (-1750 2500);
DISPLAY INVISIBLE (-1750 2500);
FORCEPROP 2 LAST CDS_LIB mstr_standard
J 2
(-1750 2550);
DISPLAY 0.787234 (-1750 2550);
PAINT MONO (-1750 2550);
DISPLAY INVISIBLE (-1750 2550);
FORCEADD TAP..6
R 2
(-1750 2600);
FORCEPROP 3 LASTPIN (-1800 2600) SIG_NAME M_J_DQ<19>
J 0
(-1790 2610);
DISPLAY 0.659574 (-1790 2610);
PAINT MONO (-1790 2610);
DISPLAY INVISIBLE (-1790 2610);
FORCEPROP 1 LASTPIN (-1800 2600) BN 19
J 2
(-1750 2610);
DISPLAY 0.617021 (-1750 2610);
PAINT PINK (-1750 2610);
FORCEPROP 1 LAST PATH I93
J 2
(-1750 2600);
DISPLAY 0.936170 (-1750 2600);
PAINT GREEN (-1750 2600);
DISPLAY INVISIBLE (-1750 2600);
FORCEPROP 1 LAST HDL_TAP TRUE
J 2
(-2075 2475);
DISPLAY 1.234043 (-2075 2475);
PAINT GREEN (-2075 2475);
DISPLAY INVISIBLE (-2075 2475);
FORCEPROP 1 LAST BODY_TYPE PLUMBING
J 2
(-1750 2550);
DISPLAY 1.234043 (-1750 2550);
PAINT GREEN (-1750 2550);
DISPLAY INVISIBLE (-1750 2550);
FORCEPROP 2 LAST CDS_LIB mstr_standard
J 2
(-1750 2600);
DISPLAY 0.787234 (-1750 2600);
PAINT MONO (-1750 2600);
DISPLAY INVISIBLE (-1750 2600);
FORCEADD TAP..6
R 2
(-1750 2650);
FORCEPROP 3 LASTPIN (-1800 2650) SIG_NAME M_J_DQ<20>
J 0
(-1790 2660);
DISPLAY 0.659574 (-1790 2660);
PAINT MONO (-1790 2660);
DISPLAY INVISIBLE (-1790 2660);
FORCEPROP 1 LASTPIN (-1800 2650) BN 20
J 2
(-1750 2660);
DISPLAY 0.617021 (-1750 2660);
PAINT PINK (-1750 2660);
FORCEPROP 1 LAST PATH I94
J 2
(-1750 2650);
DISPLAY 0.936170 (-1750 2650);
PAINT GREEN (-1750 2650);
DISPLAY INVISIBLE (-1750 2650);
FORCEPROP 1 LAST HDL_TAP TRUE
J 2
(-2075 2525);
DISPLAY 1.234043 (-2075 2525);
PAINT GREEN (-2075 2525);
DISPLAY INVISIBLE (-2075 2525);
FORCEPROP 1 LAST BODY_TYPE PLUMBING
J 2
(-1750 2600);
DISPLAY 1.234043 (-1750 2600);
PAINT GREEN (-1750 2600);
DISPLAY INVISIBLE (-1750 2600);
FORCEPROP 2 LAST CDS_LIB mstr_standard
J 2
(-1750 2650);
DISPLAY 0.787234 (-1750 2650);
PAINT MONO (-1750 2650);
DISPLAY INVISIBLE (-1750 2650);
FORCEADD TAP..6
R 2
(-1750 2200);
FORCEPROP 3 LASTPIN (-1800 2200) SIG_NAME M_J_DQ<11>
J 0
(-1790 2210);
DISPLAY 0.659574 (-1790 2210);
PAINT MONO (-1790 2210);
DISPLAY INVISIBLE (-1790 2210);
FORCEPROP 1 LASTPIN (-1800 2200) BN 11
J 2
(-1750 2210);
DISPLAY 0.617021 (-1750 2210);
PAINT PINK (-1750 2210);
FORCEPROP 1 LAST PATH I95
J 2
(-1750 2200);
DISPLAY 0.936170 (-1750 2200);
PAINT GREEN (-1750 2200);
DISPLAY INVISIBLE (-1750 2200);
FORCEPROP 1 LAST HDL_TAP TRUE
J 2
(-2075 2075);
DISPLAY 1.234043 (-2075 2075);
PAINT GREEN (-2075 2075);
DISPLAY INVISIBLE (-2075 2075);
FORCEPROP 1 LAST BODY_TYPE PLUMBING
J 2
(-1750 2150);
DISPLAY 1.234043 (-1750 2150);
PAINT GREEN (-1750 2150);
DISPLAY INVISIBLE (-1750 2150);
FORCEPROP 2 LAST CDS_LIB mstr_standard
J 2
(-1750 2200);
DISPLAY 0.787234 (-1750 2200);
PAINT MONO (-1750 2200);
DISPLAY INVISIBLE (-1750 2200);
FORCEADD TAP..6
R 2
(-1750 2300);
FORCEPROP 3 LASTPIN (-1800 2300) SIG_NAME M_J_DQ<13>
J 0
(-1790 2310);
DISPLAY 0.659574 (-1790 2310);
PAINT MONO (-1790 2310);
DISPLAY INVISIBLE (-1790 2310);
FORCEPROP 1 LASTPIN (-1800 2300) BN 13
J 2
(-1750 2310);
DISPLAY 0.617021 (-1750 2310);
PAINT PINK (-1750 2310);
FORCEPROP 1 LAST PATH I96
J 2
(-1750 2300);
DISPLAY 0.936170 (-1750 2300);
PAINT GREEN (-1750 2300);
DISPLAY INVISIBLE (-1750 2300);
FORCEPROP 1 LAST HDL_TAP TRUE
J 2
(-2075 2175);
DISPLAY 1.234043 (-2075 2175);
PAINT GREEN (-2075 2175);
DISPLAY INVISIBLE (-2075 2175);
FORCEPROP 1 LAST BODY_TYPE PLUMBING
J 2
(-1750 2250);
DISPLAY 1.234043 (-1750 2250);
PAINT GREEN (-1750 2250);
DISPLAY INVISIBLE (-1750 2250);
FORCEPROP 2 LAST CDS_LIB mstr_standard
J 2
(-1750 2300);
DISPLAY 0.787234 (-1750 2300);
PAINT MONO (-1750 2300);
DISPLAY INVISIBLE (-1750 2300);
FORCEADD TAP..6
R 2
(-1750 2250);
FORCEPROP 3 LASTPIN (-1800 2250) SIG_NAME M_J_DQ<12>
J 0
(-1790 2260);
DISPLAY 0.659574 (-1790 2260);
PAINT MONO (-1790 2260);
DISPLAY INVISIBLE (-1790 2260);
FORCEPROP 1 LASTPIN (-1800 2250) BN 12
J 2
(-1750 2260);
DISPLAY 0.617021 (-1750 2260);
PAINT PINK (-1750 2260);
FORCEPROP 1 LAST PATH I97
J 2
(-1750 2250);
DISPLAY 0.936170 (-1750 2250);
PAINT GREEN (-1750 2250);
DISPLAY INVISIBLE (-1750 2250);
FORCEPROP 1 LAST HDL_TAP TRUE
J 2
(-2075 2125);
DISPLAY 1.234043 (-2075 2125);
PAINT GREEN (-2075 2125);
DISPLAY INVISIBLE (-2075 2125);
FORCEPROP 1 LAST BODY_TYPE PLUMBING
J 2
(-1750 2200);
DISPLAY 1.234043 (-1750 2200);
PAINT GREEN (-1750 2200);
DISPLAY INVISIBLE (-1750 2200);
FORCEPROP 2 LAST CDS_LIB mstr_standard
J 2
(-1750 2250);
DISPLAY 0.787234 (-1750 2250);
PAINT MONO (-1750 2250);
DISPLAY INVISIBLE (-1750 2250);
FORCEADD TAP..6
R 2
(-1750 2350);
FORCEPROP 3 LASTPIN (-1800 2350) SIG_NAME M_J_DQ<14>
J 0
(-1790 2360);
DISPLAY 0.659574 (-1790 2360);
PAINT MONO (-1790 2360);
DISPLAY INVISIBLE (-1790 2360);
FORCEPROP 1 LASTPIN (-1800 2350) BN 14
J 2
(-1750 2360);
DISPLAY 0.617021 (-1750 2360);
PAINT PINK (-1750 2360);
FORCEPROP 1 LAST PATH I98
J 2
(-1750 2350);
DISPLAY 0.936170 (-1750 2350);
PAINT GREEN (-1750 2350);
DISPLAY INVISIBLE (-1750 2350);
FORCEPROP 1 LAST HDL_TAP TRUE
J 2
(-2075 2225);
DISPLAY 1.234043 (-2075 2225);
PAINT GREEN (-2075 2225);
DISPLAY INVISIBLE (-2075 2225);
FORCEPROP 1 LAST BODY_TYPE PLUMBING
J 2
(-1750 2300);
DISPLAY 1.234043 (-1750 2300);
PAINT GREEN (-1750 2300);
DISPLAY INVISIBLE (-1750 2300);
FORCEPROP 2 LAST CDS_LIB mstr_standard
J 2
(-1750 2350);
DISPLAY 0.787234 (-1750 2350);
PAINT MONO (-1750 2350);
DISPLAY INVISIBLE (-1750 2350);
FORCEADD TAP..6
R 2
(-1750 2400);
FORCEPROP 3 LASTPIN (-1800 2400) SIG_NAME M_J_DQ<15>
J 0
(-1790 2410);
DISPLAY 0.659574 (-1790 2410);
PAINT MONO (-1790 2410);
DISPLAY INVISIBLE (-1790 2410);
FORCEPROP 1 LASTPIN (-1800 2400) BN 15
J 2
(-1750 2410);
DISPLAY 0.617021 (-1750 2410);
PAINT PINK (-1750 2410);
FORCEPROP 1 LAST PATH I99
J 2
(-1750 2400);
DISPLAY 0.936170 (-1750 2400);
PAINT GREEN (-1750 2400);
DISPLAY INVISIBLE (-1750 2400);
FORCEPROP 1 LAST HDL_TAP TRUE
J 2
(-2075 2275);
DISPLAY 1.234043 (-2075 2275);
PAINT GREEN (-2075 2275);
DISPLAY INVISIBLE (-2075 2275);
FORCEPROP 1 LAST BODY_TYPE PLUMBING
J 2
(-1750 2350);
DISPLAY 1.234043 (-1750 2350);
PAINT GREEN (-1750 2350);
DISPLAY INVISIBLE (-1750 2350);
FORCEPROP 2 LAST CDS_LIB mstr_standard
J 2
(-1750 2400);
DISPLAY 0.787234 (-1750 2400);
PAINT MONO (-1750 2400);
DISPLAY INVISIBLE (-1750 2400);
FORCEADD INTEL_CORP_BPAGE..1
(2650 500);
FORCEPROP 1 LAST CDS_CON_LAST_MODIFIED Fri Jun 16 17:48:30 2017
J 0
(1225 825);
DISPLAY 0.787234 (1225 825);
PAINT ORANGE (1225 825);
DISPLAY INVISIBLE (1225 825);
FORCEPROP 1 LAST CUSTOM_TXT_CDS <CURRENT_DESIGN_SHEET> OF <TOTAL_DESIGN_SHEETS>
J 0
(2150 525);
PAINT ORANGE (2150 525);
FORCEPROP 1 LAST CUSTOM_TXT_CDS <CON_LAST_MODIFIED>
J 0
(-1350 600);
PAINT ORANGE (-1350 600);
FORCEPROP 2 LAST CUSTOM_TXT_CDS <XR_PAGE_TITLE>
J 0
(-5240 5750);
DISPLAY 0.638298 (-5240 5750);
PAINT PINK (-5240 5750);
DISPLAY INVISIBLE (-5240 5750);
FORCEPROP 1 LAST SCH_TITLE CPU1 DDR4 CH J DIMM1
J 0
(-5300 550);
DISPLAY 1.212766 (-5300 550);
PAINT WHITE (-5300 550);
FORCEPROP 1 LAST COMMENT_BODY TRUE
J 0
(2660 510);
DISPLAY 0.382979 (2660 510);
PAINT GREEN (2660 510);
DISPLAY INVISIBLE (2660 510);
FORCEPROP 2 LAST PAGE_BORDER TRUE
J 0
(-5240 5750);
DISPLAY 0.680851 (-5240 5750);
PAINT PINK (-5240 5750);
DISPLAY INVISIBLE (-5240 5750);
FORCEPROP 2 LAST CDS_LIB mstr_symbols
J 0
(2650 500);
DISPLAY 0.787234 (2650 500);
PAINT MONO (2650 500);
DISPLAY INVISIBLE (2650 500);
FORCEPROP 2 LAST CDS_XR_PAGE_TITLE CR-82 : @BASEBOARD_FAB2_LIB.BASEBOARD_FAB2(SCH_1):PAGE82
J 0
(-5240 5750);
DISPLAY 0.638298 (-5240 5750);
PAINT PINK (-5240 5750);
DISPLAY INVISIBLE (-5240 5750);
FORCEADD BOM_NOTE..1
(-5025 5275);
FORCEPROP 0 LAST L1 UNSTUFF FOR SKU B
J 0
(-5175 5175);
DISPLAY 1.063830 (-5175 5175);
PAINT WHITE (-5175 5175);
FORCEPROP 2 LAST ROOM SB_HEADERS
J 0
(-5175 5250);
DISPLAY 1.361702 (-5175 5250);
PAINT ORANGE (-5175 5250);
DISPLAY INVISIBLE (-5175 5250);
FORCEPROP 1 LAST COMMENT_BODY TRUE
J 0
(-5000 5375);
DISPLAY 1.319149 (-5000 5375);
PAINT ORANGE (-5000 5375);
DISPLAY INVISIBLE (-5000 5375);
FORCEPROP 2 LAST CDS_LIB mstr_symbols
J 0
(-5025 5275);
PAINT ORANGE (-5025 5275);
DISPLAY INVISIBLE (-5025 5275);
FORCEPROP 2 LAST BOM_COST SB
J 0
(-5175 5250);
DISPLAY 1.361702 (-5175 5250);
PAINT ORANGE (-5175 5250);
DISPLAY INVISIBLE (-5175 5250);
WIRE 16 -1 (-1400 2525)(-1400 2450);
WIRE 16 -1 (-1400 2450)(-1000 2450);
WIRE 16 -1 (-1000 2400)(-1000 2450);
WIRE 16 -1 (-1000 2450)(-850 2450);
WIRE 16 -1 (-1000 2350)(-1000 2400);
WIRE 16 -1 (-1000 2400)(-850 2400);
WIRE 16 -1 (-1000 2300)(-1000 2350);
WIRE 16 -1 (-1000 2350)(-850 2350);
WIRE 16 -1 (-1000 2250)(-1000 2300);
WIRE 16 -1 (-1000 2300)(-850 2300);
WIRE 16 -1 (-1000 2200)(-1000 2250);
WIRE 16 -1 (-1000 2250)(-850 2250);
WIRE 16 -1 (-1000 2150)(-1000 2200);
WIRE 16 -1 (-1000 2200)(-850 2200);
WIRE 16 -1 (-1000 2100)(-1000 2150);
WIRE 16 -1 (-1000 2150)(-850 2150);
WIRE 16 -1 (-1000 2050)(-1000 2100);
WIRE 16 -1 (-1000 2100)(-850 2100);
WIRE 16 -1 (-1000 2000)(-1000 2050);
WIRE 16 -1 (-1000 2050)(-850 2050);
WIRE 16 -1 (-1000 1950)(-1000 2000);
WIRE 16 -1 (-1000 2000)(-850 2000);
WIRE 16 -1 (-1000 1900)(-1000 1950);
WIRE 16 -1 (-1000 1950)(-850 1950);
WIRE 16 -1 (-1000 1850)(-1000 1900);
WIRE 16 -1 (-1000 1900)(-850 1900);
WIRE 16 -1 (-1000 1800)(-1000 1850);
WIRE 16 -1 (-1000 1850)(-850 1850);
WIRE 16 -1 (-1000 1750)(-1000 1800);
WIRE 16 -1 (-1000 1800)(-850 1800);
WIRE 16 -1 (-1000 1700)(-1000 1750);
WIRE 16 -1 (-1000 1750)(-850 1750);
WIRE 16 -1 (-1000 1650)(-1000 1700);
WIRE 16 -1 (-1000 1700)(-850 1700);
WIRE 16 -1 (-1000 1600)(-1000 1650);
WIRE 16 -1 (-1000 1650)(-850 1650);
WIRE 16 -1 (-1000 1550)(-1000 1600);
WIRE 16 -1 (-1000 1600)(-850 1600);
WIRE 16 -1 (-1000 1500)(-1000 1550);
WIRE 16 -1 (-1000 1550)(-850 1550);
WIRE 16 -1 (-1000 1450)(-1000 1500);
WIRE 16 -1 (-1000 1500)(-850 1500);
WIRE 16 -1 (-1000 1400)(-1000 1450);
WIRE 16 -1 (-1000 1450)(-850 1450);
WIRE 16 -1 (-1000 1350)(-1000 1400);
WIRE 16 -1 (-1000 1400)(-850 1400);
WIRE 16 -1 (-1000 1300)(-1000 1350);
WIRE 16 -1 (-1000 1350)(-850 1350);
WIRE 16 -1 (-1000 1250)(-1000 1300);
WIRE 16 -1 (-1000 1300)(-850 1300);
WIRE 16 -1 (-1000 1200)(-1000 1250);
WIRE 16 -1 (-1000 1250)(-850 1250);
WIRE 16 -1 (-1000 1200)(-850 1200);
WIRE 16 -1 (-1200 2700)(-1200 2600);
WIRE 16 -1 (-1200 2600)(-1000 2600);
WIRE 16 -1 (-1000 2550)(-1000 2600);
WIRE 16 -1 (-1000 2600)(-850 2600);
WIRE 16 -1 (-1000 2550)(-850 2550);
WIRE 16 -1 (2450 1100)(2450 1200);
WIRE 16 -1 (2450 1200)(2450 1250);
WIRE 16 -1 (2450 1200)(2250 1200);
WIRE 16 -1 (2450 1250)(2450 1300);
WIRE 16 -1 (2450 1250)(2250 1250);
WIRE 16 -1 (2450 1300)(2450 1350);
WIRE 16 -1 (2450 1300)(2250 1300);
WIRE 16 -1 (2450 1350)(2450 1400);
WIRE 16 -1 (2450 1350)(2250 1350);
WIRE 16 -1 (2450 1400)(2450 1450);
WIRE 16 -1 (2450 1400)(2250 1400);
WIRE 16 -1 (2450 1450)(2450 1500);
WIRE 16 -1 (2450 1450)(2250 1450);
WIRE 16 -1 (2450 1500)(2450 1550);
WIRE 16 -1 (2450 1500)(2250 1500);
WIRE 16 -1 (2450 1550)(2450 1600);
WIRE 16 -1 (2450 1550)(2250 1550);
WIRE 16 -1 (2450 1600)(2450 1650);
WIRE 16 -1 (2450 1600)(2250 1600);
WIRE 16 -1 (2450 1650)(2450 1700);
WIRE 16 -1 (2450 1650)(2250 1650);
WIRE 16 -1 (2450 1700)(2450 1750);
WIRE 16 -1 (2450 1700)(2250 1700);
WIRE 16 -1 (2450 1750)(2450 1800);
WIRE 16 -1 (2450 1750)(2250 1750);
WIRE 16 -1 (2450 1800)(2450 1850);
WIRE 16 -1 (2450 1800)(2250 1800);
WIRE 16 -1 (2450 1850)(2450 1900);
WIRE 16 -1 (2450 1850)(2250 1850);
WIRE 16 -1 (2450 1900)(2450 1950);
WIRE 16 -1 (2450 1900)(2250 1900);
WIRE 16 -1 (2450 1950)(2450 2000);
WIRE 16 -1 (2450 1950)(2250 1950);
WIRE 16 -1 (2450 2000)(2450 2050);
WIRE 16 -1 (2450 2000)(2250 2000);
WIRE 16 -1 (2450 2050)(2450 2100);
WIRE 16 -1 (2450 2050)(2250 2050);
WIRE 16 -1 (2450 2100)(2450 2150);
WIRE 16 -1 (2450 2100)(2250 2100);
WIRE 16 -1 (2450 2150)(2450 2200);
WIRE 16 -1 (2450 2150)(2250 2150);
WIRE 16 -1 (2450 2200)(2450 2250);
WIRE 16 -1 (2450 2200)(2250 2200);
WIRE 16 -1 (2450 2250)(2450 2300);
WIRE 16 -1 (2450 2250)(2250 2250);
WIRE 16 -1 (2450 2300)(2450 2350);
WIRE 16 -1 (2450 2300)(2250 2300);
WIRE 16 -1 (2450 2350)(2450 2400);
WIRE 16 -1 (2450 2350)(2250 2350);
WIRE 16 -1 (2450 2400)(2450 2450);
WIRE 16 -1 (2450 2400)(2250 2400);
WIRE 16 -1 (2450 2450)(2450 2500);
WIRE 16 -1 (2450 2450)(2250 2450);
WIRE 16 -1 (2450 2500)(2450 2550);
WIRE 16 -1 (2450 2500)(2250 2500);
WIRE 16 -1 (2450 2550)(2450 2600);
WIRE 16 -1 (2450 2550)(2250 2550);
WIRE 16 -1 (2450 2600)(2450 2650);
WIRE 16 -1 (2450 2600)(2250 2600);
WIRE 16 -1 (2450 2650)(2450 2700);
WIRE 16 -1 (2450 2650)(2250 2650);
WIRE 16 -1 (2450 2700)(2450 2750);
WIRE 16 -1 (2450 2700)(2250 2700);
WIRE 16 -1 (2450 2750)(2450 2800);
WIRE 16 -1 (2450 2750)(2250 2750);
WIRE 16 -1 (2450 2800)(2450 2850);
WIRE 16 -1 (2450 2800)(2250 2800);
WIRE 16 -1 (2450 2850)(2450 2900);
WIRE 16 -1 (2450 2850)(2250 2850);
WIRE 16 -1 (2450 2900)(2450 2950);
WIRE 16 -1 (2450 2900)(2250 2900);
WIRE 16 -1 (2450 2950)(2450 3000);
WIRE 16 -1 (2450 2950)(2250 2950);
WIRE 16 -1 (2450 3000)(2450 3050);
WIRE 16 -1 (2450 3000)(2250 3000);
WIRE 16 -1 (2450 3050)(2450 3100);
WIRE 16 -1 (2450 3050)(2250 3050);
WIRE 16 -1 (2450 3100)(2450 3150);
WIRE 16 -1 (2450 3100)(2250 3100);
WIRE 16 -1 (2450 3150)(2450 3200);
WIRE 16 -1 (2450 3150)(2250 3150);
WIRE 16 -1 (2450 3200)(2450 3250);
WIRE 16 -1 (2450 3200)(2250 3200);
WIRE 16 -1 (2450 3250)(2450 3300);
WIRE 16 -1 (2450 3250)(2250 3250);
WIRE 16 -1 (2450 3300)(2450 3350);
WIRE 16 -1 (2450 3300)(2250 3300);
WIRE 16 -1 (2450 3350)(2450 3400);
WIRE 16 -1 (2450 3350)(2250 3350);
WIRE 16 -1 (2450 3400)(2450 3450);
WIRE 16 -1 (2450 3400)(2250 3400);
WIRE 16 -1 (2450 3450)(2450 3500);
WIRE 16 -1 (2450 3450)(2250 3450);
WIRE 16 -1 (2450 3500)(2250 3500);
WIRE 16 -1 (-4500 1350)(-4500 1200);
WIRE 16 -1 (-1050 2975)(-1050 2900);
WIRE 16 -1 (-1050 2900)(-1050 2850);
WIRE 16 -1 (-1050 2900)(-850 2900);
WIRE 16 -1 (-1050 2850)(-1050 2800);
WIRE 16 -1 (-1050 2850)(-850 2850);
WIRE 16 -1 (-1050 2800)(-1050 2750);
WIRE 16 -1 (-1050 2800)(-850 2800);
WIRE 16 -1 (-1050 2750)(-1050 2700);
WIRE 16 -1 (-1050 2750)(-850 2750);
WIRE 16 -1 (-1050 2700)(-850 2700);
WIRE 16 -1 (-5200 2100)(-5200 2000);
WIRE 16 -1 (-3150 2000)(-5200 2000);
WIRE 16 -1 (-3150 2000)(-3150 1950);
WIRE 16 -1 (-3000 2000)(-3150 2000);
WIRE 16 -1 (-3150 1850)(-3150 1950);
WIRE 16 -1 (-3150 1950)(-3000 1950);
WIRE 16 -1 (-3150 1850)(-3000 1850);
WIRE 16 -1 (-5200 1900)(-5200 1850);
WIRE 16 -1 (-3000 1900)(-5200 1900);
WIRE 16 -1 (350 2900)(350 2975);
WIRE 16 -1 (350 2850)(350 2900);
WIRE 16 -1 (150 2900)(350 2900);
WIRE 16 -1 (150 2850)(350 2850);
WIRE 16 -1 (1050 1100)(1050 1200);
WIRE 16 -1 (1050 1200)(1050 1250);
WIRE 16 -1 (1050 1200)(1250 1200);
WIRE 16 -1 (1050 1250)(1050 1300);
WIRE 16 -1 (1050 1250)(1250 1250);
WIRE 16 -1 (1050 1300)(1050 1350);
WIRE 16 -1 (1050 1300)(1250 1300);
WIRE 16 -1 (1050 1350)(1050 1400);
WIRE 16 -1 (1050 1350)(1250 1350);
WIRE 16 -1 (1050 1400)(1050 1450);
WIRE 16 -1 (1050 1400)(1250 1400);
WIRE 16 -1 (1050 1450)(1050 1500);
WIRE 16 -1 (1050 1450)(1250 1450);
WIRE 16 -1 (1050 1500)(1050 1550);
WIRE 16 -1 (1050 1500)(1250 1500);
WIRE 16 -1 (1050 1550)(1050 1600);
WIRE 16 -1 (1050 1550)(1250 1550);
WIRE 16 -1 (1050 1600)(1050 1650);
WIRE 16 -1 (1050 1600)(1250 1600);
WIRE 16 -1 (1050 1650)(1050 1700);
WIRE 16 -1 (1050 1650)(1250 1650);
WIRE 16 -1 (1050 1700)(1050 1750);
WIRE 16 -1 (1050 1700)(1250 1700);
WIRE 16 -1 (1050 1750)(1050 1800);
WIRE 16 -1 (1050 1750)(1250 1750);
WIRE 16 -1 (1050 1800)(1050 1850);
WIRE 16 -1 (1050 1800)(1250 1800);
WIRE 16 -1 (1050 1850)(1050 1900);
WIRE 16 -1 (1050 1850)(1250 1850);
WIRE 16 -1 (1050 1900)(1050 1950);
WIRE 16 -1 (1050 1900)(1250 1900);
WIRE 16 -1 (1050 1950)(1050 2000);
WIRE 16 -1 (1050 1950)(1250 1950);
WIRE 16 -1 (1050 2000)(1050 2050);
WIRE 16 -1 (1050 2000)(1250 2000);
WIRE 16 -1 (1050 2050)(1050 2100);
WIRE 16 -1 (1050 2050)(1250 2050);
WIRE 16 -1 (1050 2100)(1050 2150);
WIRE 16 -1 (1050 2100)(1250 2100);
WIRE 16 -1 (1050 2150)(1050 2200);
WIRE 16 -1 (1050 2150)(1250 2150);
WIRE 16 -1 (1050 2200)(1050 2250);
WIRE 16 -1 (1050 2200)(1250 2200);
WIRE 16 -1 (1050 2250)(1050 2300);
WIRE 16 -1 (1050 2250)(1250 2250);
WIRE 16 -1 (1050 2300)(1050 2350);
WIRE 16 -1 (1050 2300)(1250 2300);
WIRE 16 -1 (1050 2350)(1050 2400);
WIRE 16 -1 (1050 2350)(1250 2350);
WIRE 16 -1 (1050 2400)(1050 2450);
WIRE 16 -1 (1050 2400)(1250 2400);
WIRE 16 -1 (1050 2450)(1050 2500);
WIRE 16 -1 (1050 2450)(1250 2450);
WIRE 16 -1 (1050 2500)(1050 2550);
WIRE 16 -1 (1050 2500)(1250 2500);
WIRE 16 -1 (1050 2550)(1050 2600);
WIRE 16 -1 (1050 2550)(1250 2550);
WIRE 16 -1 (1050 2600)(1050 2650);
WIRE 16 -1 (1050 2600)(1250 2600);
WIRE 16 -1 (1050 2650)(1050 2700);
WIRE 16 -1 (1050 2650)(1250 2650);
WIRE 16 -1 (1050 2700)(1050 2750);
WIRE 16 -1 (1050 2700)(1250 2700);
WIRE 16 -1 (1050 2750)(1050 2800);
WIRE 16 -1 (1050 2750)(1250 2750);
WIRE 16 -1 (1050 2800)(1050 2850);
WIRE 16 -1 (1050 2800)(1250 2800);
WIRE 16 -1 (1050 2850)(1050 2900);
WIRE 16 -1 (1050 2850)(1250 2850);
WIRE 16 -1 (1050 2900)(1050 2950);
WIRE 16 -1 (1050 2900)(1250 2900);
WIRE 16 -1 (1050 2950)(1050 3000);
WIRE 16 -1 (1050 2950)(1250 2950);
WIRE 16 -1 (1050 3000)(1050 3050);
WIRE 16 -1 (1050 3000)(1250 3000);
WIRE 16 -1 (1050 3050)(1050 3100);
WIRE 16 -1 (1050 3050)(1250 3050);
WIRE 16 -1 (1050 3100)(1050 3150);
WIRE 16 -1 (1050 3100)(1250 3100);
WIRE 16 -1 (1050 3150)(1050 3200);
WIRE 16 -1 (1050 3150)(1250 3150);
WIRE 16 -1 (1050 3200)(1050 3250);
WIRE 16 -1 (1050 3200)(1250 3200);
WIRE 16 -1 (1050 3250)(1050 3300);
WIRE 16 -1 (1050 3250)(1250 3250);
WIRE 16 -1 (1050 3300)(1050 3350);
WIRE 16 -1 (1050 3300)(1250 3300);
WIRE 16 -1 (1050 3350)(1050 3400);
WIRE 16 -1 (1050 3350)(1250 3350);
WIRE 16 -1 (1050 3400)(1050 3450);
WIRE 16 -1 (1050 3400)(1250 3400);
WIRE 16 -1 (1050 3450)(1050 3500);
WIRE 16 -1 (1050 3450)(1250 3450);
WIRE 16 -1 (1050 3500)(1250 3500);
WIRE 17 -1 (700 3475)(700 3575);
WIRE 17 -1 (700 3575)(700 3675);
WIRE 17 -1 (700 3675)(700 3775);
WIRE 17 -1 (700 3775)(700 3875);
WIRE 17 -1 (700 3875)(700 3975);
WIRE 17 -1 (700 3975)(700 4075);
WIRE 17 -1 (700 4075)(700 4175);
WIRE 17 -1 (700 4175)(700 4275);
WIRE 17 -1 (700 4275)(700 4375);
WIRE 17 -1 (700 4375)(700 4475);
WIRE 17 -1 (700 4475)(700 4575);
WIRE 17 -1 (700 4575)(700 4675);
WIRE 17 -1 (700 4675)(700 4775);
WIRE 17 -1 (700 4775)(700 4875);
WIRE 17 -1 (700 4875)(700 4975);
WIRE 17 -1 (1500 5200)(700 5200);
FORCEPROP 2 LAST SIG_NAME M_J_DQS_DP<17:0>
J 0
(950 5210);
DISPLAY 0.617021 (950 5210);
PAINT ORANGE (950 5210);
WIRE 17 -1 (700 5175)(700 5200);
WIRE 17 -1 (700 4975)(700 5075);
WIRE 17 -1 (700 5075)(700 5175);
WIRE 17 -1 (1500 5150)(900 5150);
FORCEPROP 2 LAST SIG_NAME M_J_DQS_DN<17:0>
J 0
(950 5160);
DISPLAY 0.617021 (950 5160);
PAINT ORANGE (950 5160);
WIRE 17 -1 (900 5125)(900 5150);
WIRE 17 -1 (900 3425)(900 3525);
WIRE 17 -1 (900 5025)(900 5125);
WIRE 17 -1 (900 4925)(900 5025);
WIRE 17 -1 (900 3525)(900 3625);
WIRE 17 -1 (900 3625)(900 3725);
WIRE 17 -1 (900 4825)(900 4925);
WIRE 17 -1 (900 4725)(900 4825);
WIRE 17 -1 (900 3725)(900 3825);
WIRE 17 -1 (900 3825)(900 3925);
WIRE 17 -1 (900 4625)(900 4725);
WIRE 17 -1 (900 4525)(900 4625);
WIRE 17 -1 (900 3925)(900 4025);
WIRE 17 -1 (900 4025)(900 4125);
WIRE 17 -1 (900 4425)(900 4525);
WIRE 17 -1 (900 4325)(900 4425);
WIRE 17 -1 (900 4125)(900 4225);
WIRE 17 -1 (900 4225)(900 4325);
WIRE 17 -1 (-1700 1675)(-1700 1725);
WIRE 17 -1 (-1700 1725)(-1700 1775);
WIRE 17 -1 (-1700 1775)(-1700 1825);
WIRE 17 -1 (-1700 1825)(-1700 1875);
WIRE 17 -1 (-1700 1875)(-1700 1925);
WIRE 17 -1 (-1700 1925)(-1700 1975);
WIRE 17 -1 (-1700 1975)(-1700 2025);
WIRE 17 -1 (-1700 2025)(-1700 2075);
WIRE 17 -1 (-1700 2075)(-1700 2125);
WIRE 17 -1 (-1700 2125)(-1700 2175);
WIRE 17 -1 (-1700 2175)(-1700 2225);
WIRE 17 -1 (-1700 2225)(-1700 2275);
WIRE 17 -1 (-1700 2275)(-1700 2325);
WIRE 17 -1 (-1700 2325)(-1700 2375);
WIRE 17 -1 (-1700 2375)(-1700 2425);
WIRE 17 -1 (-1700 2425)(-1700 2475);
WIRE 17 -1 (-1700 2475)(-1700 2525);
WIRE 17 -1 (-1700 2525)(-1700 2575);
WIRE 17 -1 (-1700 2575)(-1700 2625);
WIRE 17 -1 (-1700 2625)(-1700 2675);
WIRE 17 -1 (-1700 2675)(-1700 2725);
WIRE 17 -1 (-1700 2725)(-1700 2775);
WIRE 17 -1 (-1700 2775)(-1700 2825);
WIRE 17 -1 (-1700 2825)(-1700 2875);
WIRE 17 -1 (-1700 2875)(-1700 2925);
WIRE 17 -1 (-1700 2925)(-1700 2975);
WIRE 17 -1 (-1700 2975)(-1700 3025);
WIRE 17 -1 (-1700 3025)(-1700 3075);
WIRE 17 -1 (-1700 3075)(-1700 3125);
WIRE 17 -1 (-1700 3125)(-1700 3175);
WIRE 17 -1 (-1700 3175)(-1700 3225);
WIRE 17 -1 (-1700 3225)(-1700 3275);
WIRE 17 -1 (-1700 3275)(-1700 3325);
WIRE 17 -1 (-1700 3325)(-1700 3375);
WIRE 17 -1 (-1700 3375)(-1700 3425);
WIRE 17 -1 (-1700 3425)(-1700 3475);
WIRE 17 -1 (-1700 3475)(-1700 3525);
WIRE 17 -1 (-1700 3525)(-1700 3575);
WIRE 17 -1 (-1700 3575)(-1700 3625);
WIRE 17 -1 (-1700 3625)(-1700 3675);
WIRE 17 -1 (-1700 3675)(-1700 3725);
WIRE 17 -1 (-1700 3725)(-1700 3775);
WIRE 17 -1 (-1700 3775)(-1700 3825);
WIRE 17 -1 (-1700 3825)(-1700 3875);
WIRE 17 -1 (-1700 3875)(-1700 3925);
WIRE 17 -1 (-1700 3925)(-1700 3975);
WIRE 17 -1 (-1700 3975)(-1700 4025);
WIRE 17 -1 (-1700 4025)(-1700 4075);
WIRE 17 -1 (-1700 4075)(-1700 4125);
WIRE 17 -1 (-1700 4125)(-1700 4175);
WIRE 17 -1 (-1700 4175)(-1700 4225);
WIRE 17 -1 (-1700 4225)(-1700 4275);
WIRE 17 -1 (-1700 4275)(-1700 4325);
WIRE 17 -1 (-1700 4325)(-1700 4375);
WIRE 17 -1 (-1250 4850)(-1700 4850);
FORCEPROP 2 LAST SIG_NAME M_J_DQ<63:0>
J 0
(-1660 4860);
DISPLAY 0.617021 (-1660 4860);
PAINT ORANGE (-1660 4860);
WIRE 17 -1 (-1700 4375)(-1700 4425);
WIRE 17 -1 (-1700 4425)(-1700 4475);
WIRE 17 -1 (-1700 4825)(-1700 4850);
WIRE 17 -1 (-1700 4775)(-1700 4825);
WIRE 17 -1 (-1700 4475)(-1700 4525);
WIRE 17 -1 (-1700 4525)(-1700 4575);
WIRE 17 -1 (-1700 4725)(-1700 4775);
WIRE 17 -1 (-1700 4675)(-1700 4725);
WIRE 17 -1 (-1700 4575)(-1700 4625);
WIRE 17 -1 (-1700 4625)(-1700 4675);
WIRE 17 -1 (-3300 3975)(-3300 4025);
WIRE 17 -1 (-3300 4025)(-3300 4075);
WIRE 17 -1 (-3300 4075)(-3300 4125);
WIRE 17 -1 (-3300 4125)(-3300 4175);
WIRE 17 -1 (-3300 4175)(-3300 4225);
WIRE 17 -1 (-3300 4225)(-3300 4275);
WIRE 17 -1 (-3300 4275)(-3300 4325);
WIRE 17 -1 (-3300 4325)(-3300 4375);
WIRE 17 -1 (-3300 4375)(-3300 4425);
WIRE 17 -1 (-3300 4425)(-3300 4475);
WIRE 17 -1 (-3300 4475)(-3300 4525);
WIRE 17 -1 (-3300 4525)(-3300 4575);
WIRE 17 -1 (-3850 4850)(-3300 4850);
FORCEPROP 2 LAST SIG_NAME M_J_MA<17:0>
J 0
(-3800 4860);
DISPLAY 0.617021 (-3800 4860);
PAINT ORANGE (-3800 4860);
WIRE 17 -1 (-3300 4575)(-3300 4625);
WIRE 17 -1 (-3300 4625)(-3300 4675);
WIRE 17 -1 (-3300 4825)(-3300 4850);
WIRE 17 -1 (-3300 4775)(-3300 4825);
WIRE 17 -1 (-3300 4675)(-3300 4725);
WIRE 17 -1 (-3300 4725)(-3300 4775);
WIRE 17 -1 (-3500 3600)(-3850 3600);
FORCEPROP 2 LAST SIG_NAME M_J_CLK_DN<3:0>
J 0
(-3825 3610);
DISPLAY 0.617021 (-3825 3610);
PAINT ORANGE (-3825 3610);
WIRE 17 -1 (-3500 3575)(-3500 3475);
WIRE 17 -1 (-3500 3575)(-3500 3600);
WIRE 17 -1 (-3350 3350)(-3850 3350);
FORCEPROP 2 LAST SIG_NAME M_J_CS_N<7:0>
J 0
(-3825 3360);
DISPLAY 0.617021 (-3825 3360);
PAINT ORANGE (-3825 3360);
WIRE 17 -1 (-3350 3325)(-3350 3350);
WIRE 17 -1 (-3350 3275)(-3350 3325);
WIRE 17 -1 (-3350 3225)(-3350 3275);
WIRE 17 -1 (-3350 3175)(-3350 3225);
WIRE 17 -1 (-3350 3100)(-3850 3100);
FORCEPROP 2 LAST SIG_NAME M_J_CKE<3:0>
J 0
(-3825 3110);
DISPLAY 0.617021 (-3825 3110);
PAINT ORANGE (-3825 3110);
WIRE 17 -1 (-3350 3075)(-3350 3100);
WIRE 17 -1 (-3350 3025)(-3350 3075);
WIRE 17 -1 (-3350 2950)(-3850 2950);
FORCEPROP 2 LAST SIG_NAME M_J_ODT<3:0>
J 0
(-3825 2960);
DISPLAY 0.617021 (-3825 2960);
PAINT ORANGE (-3825 2960);
WIRE 17 -1 (-3350 2875)(-3350 2925);
WIRE 17 -1 (-3350 2925)(-3350 2950);
WIRE 17 -1 (-3350 2425)(-3350 2475);
WIRE 17 -1 (-3350 2475)(-3350 2525);
WIRE 17 -1 (-3350 2525)(-3350 2575);
WIRE 17 -1 (-3350 2575)(-3350 2625);
WIRE 17 -1 (-3350 2625)(-3350 2675);
WIRE 17 -1 (-3350 2800)(-3850 2800);
FORCEPROP 2 LAST SIG_NAME M_J_ECC<7:0>
J 0
(-3825 2810);
DISPLAY 0.617021 (-3825 2810);
PAINT ORANGE (-3825 2810);
WIRE 17 -1 (-3350 2775)(-3350 2800);
WIRE 17 -1 (-3350 2675)(-3350 2725);
WIRE 17 -1 (-3350 2725)(-3350 2775);
WIRE 17 -1 (-3300 3900)(-3850 3900);
FORCEPROP 2 LAST SIG_NAME M_J_BA<1:0>
J 0
(-3825 3910);
DISPLAY 0.617021 (-3825 3910);
PAINT ORANGE (-3825 3910);
WIRE 17 -1 (-3300 3900)(-3300 3875);
WIRE 17 -1 (-3300 3825)(-3300 3875);
WIRE 17 -1 (-3300 3800)(-3850 3800);
FORCEPROP 2 LAST SIG_NAME M_J_BG<1:0>
J 0
(-3825 3810);
DISPLAY 0.617021 (-3825 3810);
PAINT ORANGE (-3825 3810);
WIRE 17 -1 (-3300 3725)(-3300 3775);
WIRE 17 -1 (-3300 3775)(-3300 3800);
WIRE 17 -1 (-3300 3650)(-3850 3650);
FORCEPROP 2 LAST SIG_NAME M_J_CLK_DP<3:0>
J 0
(-3825 3660);
DISPLAY 0.617021 (-3825 3660);
PAINT ORANGE (-3825 3660);
WIRE 17 -1 (-3300 3525)(-3300 3625);
WIRE 17 -1 (-3300 3625)(-3300 3650);
WIRE 16 -1 (800 3800)(400 3800);
WIRE 16 -1 (-4500 1650)(-4500 1550);
WIRE 16 -1 (-4500 1650)(-3000 1650);
WIRE 16 -1 (-4600 1650)(-4500 1650);
FORCEPROP 2 LAST SIG_NAME M_J_VREF
J 0
(-3800 1660);
DISPLAY 0.617021 (-3800 1660);
PAINT ORANGE (-3800 1660);
WIRE 16 -1 (-1800 4800)(-2000 4800);
WIRE 16 -1 (-1800 4750)(-2000 4750);
WIRE 16 -1 (-1800 4350)(-2000 4350);
WIRE 16 -1 (-1800 4250)(-2000 4250);
WIRE 16 -1 (-1800 4700)(-2000 4700);
WIRE 16 -1 (800 4300)(400 4300);
WIRE 16 -1 (-3000 2100)(-4050 2100);
FORCEPROP 2 LAST SIG_NAME M_J_ACT_N
J 0
(-4000 2110);
DISPLAY 0.617021 (-4000 2110);
PAINT ORANGE (-4000 2110);
WIRE 16 -1 (-3500 2450)(-4275 2450);
FORCEPROP 2 LAST SIG_NAME FM_DIMM_EVENT_COD_N
J 0
(-4278 2469);
DISPLAY 0.617021 (-4278 2469);
PAINT ORANGE (-4278 2469);
WIRE 16 -1 (-3500 2200)(-3500 2450);
WIRE 16 -1 (-3500 2200)(-3000 2200);
WIRE 16 -1 (-3850 1550)(-3000 1550);
FORCEPROP 2 LAST SIG_NAME TP_CH_J_DIMM_J1_RFU_2
J 0
(-3800 1560);
DISPLAY 0.617021 (-3800 1560);
PAINT ORANGE (-3800 1560);
FORCEPROP 2 LASTPROP $XRERR UNIQUE?
J 0
(-4090 1550);
DISPLAY 0.638298 (-4090 1550);
PAINT MONO (-4090 1550);
DISPLAY INVISIBLE (-4090 1550);
WIRE 16 -1 (-3850 1450)(-3000 1450);
FORCEPROP 2 LAST SIG_NAME TP_CH_J_DIMM_J1_RFU_0
J 0
(-3800 1460);
DISPLAY 0.617021 (-3800 1460);
PAINT ORANGE (-3800 1460);
FORCEPROP 2 LASTPROP $XRERR UNIQUE?
J 0
(-4090 1450);
DISPLAY 0.638298 (-4090 1450);
PAINT MONO (-4090 1450);
DISPLAY INVISIBLE (-4090 1450);
WIRE 16 -1 (-3850 1500)(-3000 1500);
FORCEPROP 2 LAST SIG_NAME TP_CH_J_DIMM_J1_RFU_1
J 0
(-3800 1510);
DISPLAY 0.617021 (-3800 1510);
PAINT ORANGE (-3800 1510);
FORCEPROP 2 LASTPROP $XRERR UNIQUE?
J 0
(-4090 1500);
DISPLAY 0.638298 (-4090 1500);
PAINT MONO (-4090 1500);
DISPLAY INVISIBLE (-4090 1500);
WIRE 16 -1 (-3850 1750)(-3000 1750);
FORCEPROP 2 LAST SIG_NAME SMB_DDR_GHJ_VPP_SCL
J 0
(-3810 1760);
DISPLAY 0.617021 (-3810 1760);
PAINT ORANGE (-3810 1760);
WIRE 16 -1 (-3850 1800)(-3000 1800);
WIRE 16 -1 (-3850 1350)(-3000 1350);
FORCEPROP 2 LAST SIG_NAME FM_ADR_COMPLETE_GHJ_N
J 0
(-3800 1360);
DISPLAY 0.617021 (-3800 1360);
PAINT ORANGE (-3800 1360);
WIRE 16 -1 (-3400 2750)(-3850 2750);
FORCEPROP 2 LAST SIG_NAME M_J_PAR
J 0
(-3825 2760);
DISPLAY 0.617021 (-3825 2760);
PAINT ORANGE (-3825 2760);
WIRE 16 -1 (-3400 2300)(-3400 2750);
WIRE 16 -1 (-3000 2300)(-3400 2300);
WIRE 16 -1 (-3450 2700)(-3850 2700);
FORCEPROP 2 LAST SIG_NAME M_GHJ_RST_N
J 0
(-3825 2710);
DISPLAY 0.617021 (-3825 2710);
PAINT ORANGE (-3825 2710);
WIRE 16 -1 (-3450 2250)(-3450 2700);
WIRE 16 -1 (-3000 2250)(-3450 2250);
WIRE 16 -1 (-3300 3350)(-3000 3350);
WIRE 16 -1 (-3300 3400)(-3850 3400);
FORCEPROP 2 LAST SIG_NAME M_J_C<2>
J 0
(-3825 3410);
DISPLAY 0.617021 (-3825 3410);
PAINT ORANGE (-3825 3410);
WIRE 16 -1 (-3300 3400)(-3300 3350);
WIRE 16 -1 (-3000 3850)(-3200 3850);
WIRE 16 -1 (-3000 3500)(-3200 3500);
WIRE 16 -1 (-3000 3300)(-3250 3300);
WIRE 16 -1 (-3000 3250)(-3250 3250);
WIRE 16 -1 (-3000 3200)(-3250 3200);
WIRE 16 -1 (-3000 3950)(-3200 3950);
WIRE 16 -1 (-3000 4000)(-3200 4000);
WIRE 16 -1 (-3000 2700)(-3250 2700);
WIRE 16 -1 (-3000 2650)(-3250 2650);
WIRE 16 -1 (-3000 2600)(-3250 2600);
WIRE 16 -1 (-3000 2550)(-3250 2550);
WIRE 16 -1 (-3000 2500)(-3250 2500);
WIRE 16 -1 (-3000 2450)(-3250 2450);
WIRE 16 -1 (-3000 2400)(-3250 2400);
WIRE 16 -1 (-3000 3050)(-3250 3050);
WIRE 16 -1 (-3000 3600)(-3200 3600);
WIRE 16 -1 (-3000 3700)(-3200 3700);
WIRE 16 -1 (-3000 3750)(-3200 3750);
WIRE 16 -1 (-3000 3800)(-3200 3800);
WIRE 16 -1 (-3000 4050)(-3200 4050);
WIRE 16 -1 (-3000 2750)(-3250 2750);
WIRE 16 -1 (-3000 2850)(-3250 2850);
WIRE 16 -1 (-3000 2900)(-3250 2900);
WIRE 16 -1 (-3000 3000)(-3250 3000);
WIRE 16 -1 (-3000 3150)(-3250 3150);
WIRE 16 -1 (-3000 3450)(-3400 3450);
WIRE 16 -1 (-3000 3550)(-3400 3550);
WIRE 16 -1 (-3000 2150)(-4075 2150);
FORCEPROP 2 LAST SIG_NAME M_J_ALERT_N
J 0
(-4025 2160);
DISPLAY 0.617021 (-4025 2160);
PAINT ORANGE (-4025 2160);
WIRE 16 -1 (-1800 1700)(-2000 1700);
WIRE 16 -1 (-1800 1750)(-2000 1750);
WIRE 16 -1 (-1800 1650)(-2000 1650);
WIRE 16 -1 (-1800 2000)(-2000 2000);
WIRE 16 -1 (-1800 1950)(-2000 1950);
WIRE 16 -1 (-1800 1800)(-2000 1800);
WIRE 16 -1 (-1800 1850)(-2000 1850);
WIRE 16 -1 (-1800 1900)(-2000 1900);
WIRE 16 -1 (-1800 2300)(-2000 2300);
WIRE 16 -1 (-1800 2250)(-2000 2250);
WIRE 16 -1 (-1800 2200)(-2000 2200);
WIRE 16 -1 (-1800 2150)(-2000 2150);
WIRE 16 -1 (-1800 2100)(-2000 2100);
WIRE 16 -1 (-1800 2050)(-2000 2050);
WIRE 16 -1 (-1800 2550)(-2000 2550);
WIRE 16 -1 (-1800 2350)(-2000 2350);
WIRE 16 -1 (-1800 2400)(-2000 2400);
WIRE 16 -1 (-1800 2500)(-2000 2500);
WIRE 16 -1 (-1800 2450)(-2000 2450);
WIRE 16 -1 (-1800 2800)(-2000 2800);
WIRE 16 -1 (-1800 2700)(-2000 2700);
WIRE 16 -1 (-1800 2650)(-2000 2650);
WIRE 16 -1 (-1800 2600)(-2000 2600);
WIRE 16 -1 (-1800 2750)(-2000 2750);
WIRE 16 -1 (-1800 3050)(-2000 3050);
WIRE 16 -1 (-1800 2900)(-2000 2900);
WIRE 16 -1 (-1800 2850)(-2000 2850);
WIRE 16 -1 (-1800 3000)(-2000 3000);
WIRE 16 -1 (-1800 2950)(-2000 2950);
WIRE 16 -1 (-1800 3100)(-2000 3100);
WIRE 16 -1 (-1800 3300)(-2000 3300);
WIRE 16 -1 (-1800 3250)(-2000 3250);
WIRE 16 -1 (-1800 3200)(-2000 3200);
WIRE 16 -1 (-1800 3150)(-2000 3150);
WIRE 16 -1 (-1800 3350)(-2000 3350);
WIRE 16 -1 (-1800 3400)(-2000 3400);
WIRE 16 -1 (-1800 3550)(-2000 3550);
WIRE 16 -1 (-1800 3450)(-2000 3450);
WIRE 16 -1 (-1800 3500)(-2000 3500);
WIRE 16 -1 (-1800 3800)(-2000 3800);
WIRE 16 -1 (-1800 3750)(-2000 3750);
WIRE 16 -1 (-1800 3650)(-2000 3650);
WIRE 16 -1 (-1800 3600)(-2000 3600);
WIRE 16 -1 (-1800 3700)(-2000 3700);
WIRE 16 -1 (-1800 3950)(-2000 3950);
WIRE 16 -1 (-1800 3900)(-2000 3900);
WIRE 16 -1 (-1800 3850)(-2000 3850);
WIRE 16 -1 (-1800 4050)(-2000 4050);
WIRE 16 -1 (-1800 4000)(-2000 4000);
WIRE 16 -1 (-3000 4550)(-3200 4550);
WIRE 16 -1 (-3000 4600)(-3200 4600);
WIRE 16 -1 (-3000 4800)(-3200 4800);
WIRE 16 -1 (-3000 4100)(-3200 4100);
WIRE 16 -1 (-3000 4150)(-3200 4150);
WIRE 16 -1 (-3000 4200)(-3200 4200);
WIRE 16 -1 (-3000 4250)(-3200 4250);
WIRE 16 -1 (-3000 4300)(-3200 4300);
WIRE 16 -1 (-3000 4350)(-3200 4350);
WIRE 16 -1 (-3000 4400)(-3200 4400);
WIRE 16 -1 (-3000 4450)(-3200 4450);
WIRE 16 -1 (-3000 4500)(-3200 4500);
WIRE 16 -1 (-3000 4650)(-3200 4650);
WIRE 16 -1 (-3000 4700)(-3200 4700);
WIRE 16 -1 (-3000 4750)(-3200 4750);
WIRE 16 -1 (-1800 4300)(-2000 4300);
WIRE 16 -1 (-1800 4200)(-2000 4200);
WIRE 16 -1 (-1800 4150)(-2000 4150);
WIRE 16 -1 (-1800 4100)(-2000 4100);
WIRE 16 -1 (-1800 4600)(-2000 4600);
WIRE 16 -1 (-1800 4450)(-2000 4450);
WIRE 16 -1 (-1800 4400)(-2000 4400);
WIRE 16 -1 (-1800 4500)(-2000 4500);
WIRE 16 -1 (-1800 4550)(-2000 4550);
WIRE 16 -1 (-1800 4650)(-2000 4650);
WIRE 16 -1 (800 3400)(400 3400);
WIRE 16 -1 (600 3450)(400 3450);
WIRE 16 -1 (800 3500)(400 3500);
WIRE 16 -1 (600 3550)(400 3550);
WIRE 16 -1 (800 3600)(400 3600);
WIRE 16 -1 (600 3650)(400 3650);
WIRE 16 -1 (800 3700)(400 3700);
WIRE 16 -1 (600 3750)(400 3750);
WIRE 16 -1 (600 3850)(400 3850);
WIRE 16 -1 (800 3900)(400 3900);
WIRE 16 -1 (600 3950)(400 3950);
WIRE 16 -1 (800 4000)(400 4000);
WIRE 16 -1 (600 4050)(400 4050);
WIRE 16 -1 (800 4400)(400 4400);
WIRE 16 -1 (600 4450)(400 4450);
WIRE 16 -1 (800 4500)(400 4500);
WIRE 16 -1 (600 4550)(400 4550);
WIRE 16 -1 (800 4600)(400 4600);
WIRE 16 -1 (600 4650)(400 4650);
WIRE 16 -1 (800 4700)(400 4700);
WIRE 16 -1 (600 4750)(400 4750);
WIRE 16 -1 (800 4800)(400 4800);
WIRE 16 -1 (600 4850)(400 4850);
WIRE 16 -1 (800 4900)(400 4900);
WIRE 16 -1 (600 4950)(400 4950);
WIRE 16 -1 (800 5000)(400 5000);
WIRE 16 -1 (600 5050)(400 5050);
WIRE 16 -1 (800 5100)(400 5100);
WIRE 16 -1 (800 4100)(400 4100);
WIRE 16 -1 (600 4150)(400 4150);
WIRE 16 -1 (800 4200)(400 4200);
WIRE 16 -1 (600 4250)(400 4250);
WIRE 16 -1 (600 4350)(400 4350);
WIRE 16 -1 (600 5150)(400 5150);
DOT 1 (2450 2650);
DOT 1 (2450 2600);
DOT 1 (2450 1750);
DOT 1 (2450 1950);
DOT 1 (2450 1700);
DOT 1 (-1000 1350);
DOT 1 (-1000 1250);
DOT 1 (-1000 1300);
DOT 1 (-1000 1500);
DOT 1 (-1000 1450);
DOT 1 (-1000 1400);
DOT 1 (-1000 1550);
DOT 1 (-1000 1600);
DOT 1 (-1000 1650);
DOT 1 (-1000 1700);
DOT 1 (-1000 1750);
DOT 1 (-1000 1800);
DOT 1 (-1000 1850);
DOT 1 (-1000 2000);
DOT 1 (-1000 1950);
DOT 1 (-1000 2050);
DOT 1 (-1000 2150);
DOT 1 (-1000 2250);
DOT 1 (-1000 2200);
DOT 1 (-1000 2350);
DOT 1 (-1000 2400);
DOT 1 (-1000 2300);
DOT 1 (-1000 2450);
DOT 1 (-1000 2600);
DOT 1 (-1050 2800);
DOT 1 (-1050 2850);
DOT 1 (-1050 2900);
DOT 1 (-1050 2750);
DOT 1 (-3150 2000);
DOT 1 (2450 3400);
DOT 1 (2450 3450);
DOT 1 (2450 3350);
DOT 1 (2450 3300);
DOT 1 (2450 3250);
DOT 1 (2450 3150);
DOT 1 (2450 3200);
DOT 1 (2450 3100);
DOT 1 (2450 3000);
DOT 1 (2450 3050);
DOT 1 (2450 2950);
DOT 1 (2450 2900);
DOT 1 (2450 2850);
DOT 1 (2450 2750);
DOT 1 (2450 2800);
DOT 1 (2450 2700);
DOT 1 (2450 2500);
DOT 1 (2450 2550);
DOT 1 (2450 2450);
DOT 1 (2450 2400);
DOT 1 (2450 2350);
DOT 1 (2450 2250);
DOT 1 (2450 2300);
DOT 1 (2450 2100);
DOT 1 (2450 2200);
DOT 1 (2450 2150);
DOT 1 (2450 2050);
DOT 1 (2450 2000);
DOT 1 (2450 1850);
DOT 1 (2450 1900);
DOT 1 (2450 1800);
DOT 1 (2450 1600);
DOT 1 (2450 1650);
DOT 1 (2450 1550);
DOT 1 (2450 1450);
DOT 1 (2450 1500);
DOT 1 (2450 1350);
DOT 1 (2450 1400);
DOT 1 (2450 1300);
DOT 1 (2450 1250);
DOT 1 (2450 1200);
DOT 1 (1050 3400);
DOT 1 (1050 3450);
DOT 1 (1050 3350);
DOT 1 (1050 3300);
DOT 1 (1050 3200);
DOT 1 (1050 2900);
DOT 1 (1050 2850);
DOT 1 (1050 2750);
DOT 1 (1050 2800);
DOT 1 (1050 2700);
DOT 1 (1050 2650);
DOT 1 (1050 2600);
DOT 1 (1050 2400);
DOT 1 (1050 2350);
DOT 1 (1050 2250);
DOT 1 (1050 2300);
DOT 1 (1050 2200);
DOT 1 (1050 2150);
DOT 1 (1050 2100);
DOT 1 (1050 2050);
DOT 1 (1050 2000);
DOT 1 (1050 1950);
DOT 1 (1050 1850);
DOT 1 (1050 1900);
DOT 1 (1050 1800);
DOT 1 (1050 1750);
DOT 1 (1050 1700);
DOT 1 (1050 1600);
DOT 1 (1050 1650);
DOT 1 (1050 1550);
DOT 1 (1050 1450);
DOT 1 (1050 1500);
DOT 1 (1050 1350);
DOT 1 (1050 1400);
DOT 1 (1050 1300);
DOT 1 (1050 1250);
DOT 1 (1050 1200);
DOT 1 (-4500 1650);
DOT 1 (1050 2500);
DOT 1 (1050 2450);
DOT 1 (350 2900);
DOT 1 (1050 2550);
DOT 1 (1050 2950);
DOT 1 (1050 3000);
DOT 1 (1050 3050);
DOT 1 (1050 3100);
DOT 1 (1050 3150);
DOT 1 (-1000 1900);
DOT 1 (-1000 2100);
DOT 1 (-3150 1950);
DOT 1 (1050 3250);
FORCENOTE
PVDDQ (SINGLE SIDE) CAP: 10UF X1, 22UF X50
(-4050 5175) 0;
DISPLAY LEFT (-4050 5175);
DISPLAY 1.021277 (-4050 5175);
PAINT PURPLE (-4050 5175);
FORCENOTE
PVTT CAP: 100UF X2, 47UF X1
(-4050 5225) 0;
DISPLAY LEFT (-4050 5225);
DISPLAY 1.021277 (-4050 5225);
PAINT PURPLE (-4050 5225);
FORCENOTE
CAP BETWEEN DIMM
(-4050 5350) 0;
DISPLAY LEFT (-4050 5350);
DISPLAY 1.276596 (-4050 5350);
PAINT PURPLE (-4050 5350);
FORCENOTE
PVPP CAP: 10UF X12
(-4050 5275) 0;
DISPLAY LEFT (-4050 5275);
DISPLAY 1.021277 (-4050 5275);
PAINT PURPLE (-4050 5275);
FORCENOTE
PVDDQ (DOUBLE SIDE) CAP: 100UF X8, 47UF X41
(-4050 5125) 0;
DISPLAY LEFT (-4050 5125);
DISPLAY 1.021277 (-4050 5125);
PAINT PURPLE (-4050 5125);
FORCENOTE
SMBUS ADDR: 0XAA
(-5250 900) 0;
DISPLAY LEFT (-5250 900);
DISPLAY 1.957447 (-5250 900);
PAINT PURPLE (-5250 900);
FORCENOTE
PLACE CAP NEAR DIMM CONNECTOR
(-5288 1052) 0;
DISPLAY LEFT (-5288 1052);
DISPLAY 1.957447 (-5288 1052);
PAINT PURPLE (-5288 1052);
QUIT
